FILE_TYPE = MACRO_DRAWING;
SET COLOR_WIRE YELLOW;
SET COLOR_PROP MONO;
SET COLOR_DOT WHITE;
SET COLOR_ARC YELLOW;
SET COLOR_BODY GREEN;
SET COLOR_NOTE MONO;
SET PROP_DISPLAY VALUE;
SET PAGE_NUMBER P226;
FORCEADD OFFPAGE..1
(-2475 200);
FORCEPROP 2 LAST $XR0 228 
J 0
(-2757 200);
DISPLAY 0.638298 (-2757 200);
PAINT MONO (-2757 200);
FORCEPROP 2 LAST CDS_LIB mstr_standard
J 0
(-2475 200);
PAINT ORANGE (-2475 200);
DISPLAY INVISIBLE (-2475 200);
FORCEPROP 2 LAST ROOM VDDQ_KLM_PWR_VR
J 0
(-3025 275);
DISPLAY 1.361702 (-3025 275);
PAINT ORANGE (-3025 275);
DISPLAY INVISIBLE (-3025 275);
FORCEPROP 2 LAST PATH I1
J 0
(-2750 250);
DISPLAY 1.021277 (-2750 250);
PAINT ORANGE (-2750 250);
DISPLAY INVISIBLE (-2750 250);
FORCEPROP 1 LAST OFFPAGE TRUE
J 0
(-2150 75);
DISPLAY 1.170213 (-2150 75);
PAINT GREEN (-2150 75);
DISPLAY INVISIBLE (-2150 75);
FORCEPROP 1 LAST COMMENT_BODY TRUE
J 0
(-2350 100);
DISPLAY 1.170213 (-2350 100);
PAINT GREEN (-2350 100);
DISPLAY INVISIBLE (-2350 100);
FORCEADD OFFPAGE..1
(-2500 1625);
FORCEPROP 2 LAST $XR0 227 
J 0
(-2752 1625);
DISPLAY 0.638298 (-2752 1625);
PAINT MONO (-2752 1625);
FORCEPROP 2 LAST ROOM VDDQ_KLM_PWR_VR
J 0
(-3050 1700);
DISPLAY 1.361702 (-3050 1700);
PAINT ORANGE (-3050 1700);
DISPLAY INVISIBLE (-3050 1700);
FORCEPROP 2 LAST CDS_LIB mstr_standard
J 0
(-2500 1625);
PAINT ORANGE (-2500 1625);
DISPLAY INVISIBLE (-2500 1625);
FORCEPROP 2 LAST PATH I10
J 0
(-2750 1675);
DISPLAY 1.021277 (-2750 1675);
PAINT ORANGE (-2750 1675);
DISPLAY INVISIBLE (-2750 1675);
FORCEPROP 1 LAST OFFPAGE TRUE
J 0
(-2175 1500);
DISPLAY 1.170213 (-2175 1500);
PAINT GREEN (-2175 1500);
DISPLAY INVISIBLE (-2175 1500);
FORCEPROP 1 LAST COMMENT_BODY TRUE
J 0
(-2375 1525);
DISPLAY 1.170213 (-2375 1525);
PAINT GREEN (-2375 1525);
DISPLAY INVISIBLE (-2375 1525);
FORCEADD OFFPAGE..1
(-2525 2350);
FORCEPROP 2 LAST $XR2 223 
J 0
(-2986 2350);
DISPLAY 0.638298 (-2986 2350);
PAINT MONO (-2986 2350);
FORCEPROP 2 LAST $XR1 193 
J 0
(-2866 2350);
DISPLAY 0.638298 (-2866 2350);
PAINT MONO (-2866 2350);
FORCEPROP 2 LAST $XR0 55 
J 0
(-2746 2350);
DISPLAY 0.638298 (-2746 2350);
PAINT MONO (-2746 2350);
FORCEPROP 2 LAST CDS_LIB mstr_standard
J 0
(-2525 2350);
PAINT ORANGE (-2525 2350);
DISPLAY INVISIBLE (-2525 2350);
FORCEPROP 2 LAST ROOM VDDQ_KLM_PWR_VR
J 0
(-3075 2425);
DISPLAY 1.361702 (-3075 2425);
PAINT ORANGE (-3075 2425);
DISPLAY INVISIBLE (-3075 2425);
FORCEPROP 2 LAST PATH I11
J 0
(-2725 2400);
DISPLAY 1.021277 (-2725 2400);
PAINT ORANGE (-2725 2400);
DISPLAY INVISIBLE (-2725 2400);
FORCEPROP 1 LAST OFFPAGE TRUE
J 0
(-2200 2225);
DISPLAY 1.170213 (-2200 2225);
PAINT GREEN (-2200 2225);
DISPLAY INVISIBLE (-2200 2225);
FORCEPROP 1 LAST COMMENT_BODY TRUE
J 0
(-2400 2250);
DISPLAY 1.170213 (-2400 2250);
PAINT GREEN (-2400 2250);
DISPLAY INVISIBLE (-2400 2250);
FORCEADD CAP..1
(-1750 325);
FORCEPROP 1 LASTPIN (-1750 425) $PN 1
J 0
(-1740 405);
DISPLAY 0.617021 (-1740 405);
PAINT ORANGE (-1740 405);
FORCEPROP 1 LAST VALUE 220PF
J 0
(-1700 375);
DISPLAY 0.617021 (-1700 375);
PAINT SKYBLUE (-1700 375);
FORCEPROP 1 LAST TOLERANCE 10%
J 0
(-1525 375);
DISPLAY 0.617021 (-1525 375);
PAINT SKYBLUE (-1525 375);
FORCEPROP 1 LASTPIN (-1750 225) $PN 2
J 0
(-1740 205);
DISPLAY 0.617021 (-1740 205);
PAINT ORANGE (-1740 205);
FORCEPROP 1 LAST PACK_TYPE 0402LF
J 0
(-1700 225);
DISPLAY 0.617021 (-1700 225);
PAINT SKYBLUE (-1700 225);
FORCEPROP 1 LAST PART_NUMBER A36096-050
J 0
(-1700 275);
DISPLAY 0.617021 (-1700 275);
PAINT BLUE (-1700 275);
FORCEPROP 1 LAST LOCATION C1B12
J 0
(-1700 425);
DISPLAY 0.617021 (-1700 425);
PAINT AQUA (-1700 425);
FORCEPROP 1 LAST VOLTAGE 50V
J 0
(-1700 325);
DISPLAY 0.617021 (-1700 325);
PAINT SKYBLUE (-1700 325);
FORCEPROP 1 LAST MATERIAL X7R
J 0
(-1575 325);
DISPLAY 0.617021 (-1575 325);
PAINT SKYBLUE (-1575 325);
FORCEPROP 2 LAST CDS_LIB mstr_discrete
J 0
(-1750 325);
PAINT ORANGE (-1750 325);
DISPLAY INVISIBLE (-1750 325);
FORCEPROP 2 LAST CDS_LOCATION C1B12
J 0
(-1700 425);
DISPLAY 0.617021 (-1700 425);
PAINT AQUA (-1700 425);
DISPLAY INVISIBLE (-1700 425);
FORCEPROP 2 LAST SEC 1
J 0
(-1700 550);
DISPLAY 0.680851 (-1700 550);
PAINT MONO (-1700 550);
DISPLAY INVISIBLE (-1700 550);
FORCEPROP 2 LAST NO_XNET_CONNECTION 1
J 0
(-1700 525);
PAINT MONO (-1700 525);
DISPLAY INVISIBLE (-1700 525);
FORCEPROP 2 LAST ROOM VDDQ_KLM_PWR_VR
J 0
(-1700 475);
DISPLAY 1.361702 (-1700 475);
PAINT ORANGE (-1700 475);
DISPLAY INVISIBLE (-1700 475);
FORCEPROP 2 LAST SEC_TYPE 0402LF
J 0
(-1700 550);
DISPLAY 1.021277 (-1700 550);
PAINT ORANGE (-1700 550);
DISPLAY INVISIBLE (-1700 550);
FORCEPROP 0 LAST CDS_SEC 1
J 0
(-1700 475);
PAINT MONO (-1700 475);
DISPLAY INVISIBLE (-1700 475);
FORCEPROP 1 LAST PATH I12
J 0
(-1700 475);
DISPLAY 0.978723 (-1700 475);
PAINT WHITE (-1700 475);
DISPLAY INVISIBLE (-1700 475);
FORCEADD RES..1
(-1925 475);
FORCEPROP 1 LAST LOCATION R1B16
J 0
(-1975 525);
DISPLAY 0.617021 (-1975 525);
PAINT AQUA (-1975 525);
FORCEPROP 1 LAST PART_NUMBER G21796-066
J 0
(-2075 425);
DISPLAY 0.617021 (-2075 425);
PAINT BLUE (-2075 425);
FORCEPROP 1 LAST PACK_TYPE 0402
J 0
(-1900 375);
DISPLAY 0.617021 (-1900 375);
PAINT SKYBLUE (-1900 375);
FORCEPROP 1 LAST MATERIAL CHIP
J 0
(-1900 325);
DISPLAY 0.617021 (-1900 325);
PAINT SKYBLUE (-1900 325);
FORCEPROP 1 LASTPIN (-1825 475) $PN 2
J 0
(-1863 487);
DISPLAY 0.617021 (-1863 487);
PAINT ORANGE (-1863 487);
FORCEPROP 1 LAST TOLERANCE 1%
J 0
(-2000 375);
DISPLAY 0.617021 (-2000 375);
PAINT SKYBLUE (-2000 375);
FORCEPROP 1 LASTPIN (-2025 475) $PN 1
J 0
(-2013 487);
DISPLAY 0.617021 (-2013 487);
PAINT ORANGE (-2013 487);
FORCEPROP 1 LAST VALUE 10.0
J 2
(-2025 375);
DISPLAY 0.617021 (-2025 375);
PAINT SKYBLUE (-2025 375);
FORCEPROP 1 LAST WATTAGE 1/16W
J 2
(-1925 325);
DISPLAY 0.617021 (-1925 325);
PAINT SKYBLUE (-1925 325);
FORCEPROP 2 LAST NO_XNET_CONNECTION 1
J 0
(-1975 675);
PAINT MONO (-1975 675);
DISPLAY INVISIBLE (-1975 675);
FORCEPROP 2 LAST SEC 1
J 0
(-1975 700);
DISPLAY 0.680851 (-1975 700);
PAINT MONO (-1975 700);
DISPLAY INVISIBLE (-1975 700);
FORCEPROP 2 LAST SEC_TYPE 0402
J 0
(-1975 700);
DISPLAY 1.021277 (-1975 700);
PAINT ORANGE (-1975 700);
DISPLAY INVISIBLE (-1975 700);
FORCEPROP 2 LAST ROOM VDDQ_KLM_PWR_VR
J 0
(-1850 575);
DISPLAY 1.361702 (-1850 575);
PAINT ORANGE (-1850 575);
DISPLAY INVISIBLE (-1850 575);
FORCEPROP 2 LAST CDS_LOCATION R1B16
J 0
(-1975 525);
DISPLAY 0.617021 (-1975 525);
PAINT AQUA (-1975 525);
DISPLAY INVISIBLE (-1975 525);
FORCEPROP 2 LAST CDS_LIB mstr_discrete
J 0
(-1925 475);
PAINT ORANGE (-1925 475);
DISPLAY INVISIBLE (-1925 475);
FORCEPROP 0 LAST CDS_SEC 1
J 0
(-1975 575);
PAINT MONO (-1975 575);
DISPLAY INVISIBLE (-1975 575);
FORCEPROP 1 LAST PATH I13
J 0
(-1975 625);
DISPLAY 0.978723 (-1975 625);
PAINT WHITE (-1975 625);
DISPLAY INVISIBLE (-1975 625);
FORCEADD RES..1
(-1800 775);
FORCEPROP 1 LAST PART_NUMBER G21497-005
J 0
(-1950 725);
DISPLAY 0.617021 (-1950 725);
PAINT BLUE (-1950 725);
FORCEPROP 1 LAST TOLERANCE 5%
J 0
(-1850 675);
DISPLAY 0.617021 (-1850 675);
PAINT SKYBLUE (-1850 675);
FORCEPROP 1 LAST PACK_TYPE 0402
J 0
(-1725 675);
DISPLAY 0.617021 (-1725 675);
PAINT SKYBLUE (-1725 675);
FORCEPROP 1 LAST LOCATION R9M9
J 0
(-1850 825);
DISPLAY 0.617021 (-1850 825);
PAINT AQUA (-1850 825);
FORCEPROP 1 LAST MATERIAL CHIP
J 0
(-1800 625);
DISPLAY 0.617021 (-1800 625);
PAINT SKYBLUE (-1800 625);
FORCEPROP 1 LAST WATTAGE 1/16W
J 2
(-1825 625);
DISPLAY 0.617021 (-1825 625);
PAINT SKYBLUE (-1825 625);
FORCEPROP 1 LAST VALUE 0.0
J 2
(-1900 675);
DISPLAY 0.617021 (-1900 675);
PAINT SKYBLUE (-1900 675);
FORCEPROP 1 LASTPIN (-1700 775) $PN 2
J 0
(-1738 787);
DISPLAY 0.787234 (-1738 787);
PAINT ORANGE (-1738 787);
DISPLAY INVISIBLE (-1738 787);
FORCEPROP 2 LAST CDS_SEC 1
J 0
(-1850 975);
PAINT MONO (-1850 975);
DISPLAY INVISIBLE (-1850 975);
FORCEPROP 2 LAST $SEC 1
J 0
(-1850 975);
PAINT MONO (-1850 975);
DISPLAY INVISIBLE (-1850 975);
FORCEPROP 2 LAST ROOM PVCCIN_CPU0_VR
J 0
(-1850 875);
DISPLAY 1.361702 (-1850 875);
PAINT ORANGE (-1850 875);
DISPLAY INVISIBLE (-1850 875);
FORCEPROP 2 LAST CDS_LOCATION R9M9
J 0
(-1850 825);
DISPLAY 0.617021 (-1850 825);
PAINT AQUA (-1850 825);
DISPLAY INVISIBLE (-1850 825);
FORCEPROP 1 LASTPIN (-1900 775) $PN 1
J 0
(-1888 787);
DISPLAY 0.787234 (-1888 787);
PAINT ORANGE (-1888 787);
DISPLAY INVISIBLE (-1888 787);
FORCEPROP 2 LAST CDS_LIB mstr_discrete
J 0
(-1800 775);
PAINT ORANGE (-1800 775);
DISPLAY INVISIBLE (-1800 775);
FORCEPROP 1 LAST PATH I14
J 0
(-1850 925);
DISPLAY 0.978723 (-1850 925);
PAINT WHITE (-1850 925);
DISPLAY INVISIBLE (-1850 925);
FORCEADD SC22P50V2JN-4GP..1
R 1
(-1550 1850);
FORCEPROP 0 LASTPIN (-1475 1850) $PN 2
J 0
(-1465 1860);
DISPLAY 0.808511 (-1465 1860);
PAINT MONO (-1465 1860);
FORCEPROP 0 LAST GROUP POWER_FAIR
J 0
(-1690 1768);
DISPLAY 0.638298 (-1690 1768);
PAINT BROWN (-1690 1768);
DISPLAY BOTH (-1690 1768);
FORCEPROP 1 LAST VALUE SC22P50V2JN-4GP
J 0
(-1550 1725);
DISPLAY 0.617021 (-1550 1725);
PAINT GREEN (-1550 1725);
FORCEPROP 2 LAST PACK_SIZE 0402
J 0
(-1550 1625);
DISPLAY 0.638298 (-1550 1625);
PAINT GREEN (-1550 1625);
FORCEPROP 2 LAST TOLERANCE 5%
J 0
(-1550 1675);
DISPLAY 0.638298 (-1550 1675);
PAINT GREEN (-1550 1675);
FORCEPROP 0 LASTPIN (-1625 1850) $PN 1
J 2
(-1635 1860);
DISPLAY 0.808511 (-1635 1860);
PAINT MONO (-1635 1860);
FORCEPROP 2 LAST RATED 50V
J 0
(-1450 1675);
DISPLAY 0.638298 (-1450 1675);
PAINT GREEN (-1450 1675);
FORCEPROP 2 LAST TYPE NPO
J 0
(-1700 1625);
DISPLAY 0.638298 (-1700 1625);
PAINT GREEN (-1700 1625);
FORCEPROP 2 LAST ATTRIBUTE 22PF
J 0
(-1700 1675);
DISPLAY 0.638298 (-1700 1675);
PAINT GREEN (-1700 1675);
FORCEPROP 1 LAST LOCATION CF21
J 0
(-1705 1725);
DISPLAY 0.617021 (-1705 1725);
PAINT GREEN (-1705 1725);
FORCEPROP 1 LAST PATH I15
R 1
J 0
(-1550 1850);
DISPLAY 0.617021 (-1550 1850);
PAINT GREEN (-1550 1850);
DISPLAY INVISIBLE (-1550 1850);
FORCEPROP 0 LAST CDS_SEC 1
R 1
J 0
(-1700 2000);
PAINT MONO (-1700 2000);
DISPLAY INVISIBLE (-1700 2000);
FORCEPROP 0 LAST $SEC 1
R 1
J 0
(-1700 2000);
PAINT MONO (-1700 2000);
DISPLAY INVISIBLE (-1700 2000);
FORCEPROP 0 LAST CDS_LOCATION CF21
R 1
J 0
(-1700 2000);
PAINT MONO (-1700 2000);
DISPLAY INVISIBLE (-1700 2000);
FORCEPROP 2 LAST CDS_LIB w_hdl
J 0
(-1550 1850);
PAINT MONO (-1550 1850);
DISPLAY INVISIBLE (-1550 1850);
FORCEPROP 1 LAST CDS_LMAN_SYM_OUTLINE -50,25,50,-25
R 1
J 0
(-1550 1850);
DISPLAY 0.468085 (-1550 1850);
PAINT GREEN (-1550 1850);
DISPLAY INVISIBLE (-1550 1850);
FORCEPROP 1 LAST PACK_TYPE SMD-BCG
R 1
J 0
(-1550 1850);
DISPLAY 0.617021 (-1550 1850);
PAINT GREEN (-1550 1850);
DISPLAY INVISIBLE (-1550 1850);
FORCEPROP 1 LAST PART_NUMBER 78.22034.1FL
R 1
J 0
(-1550 1850);
DISPLAY 0.617021 (-1550 1850);
PAINT GREEN (-1550 1850);
DISPLAY INVISIBLE (-1550 1850);
FORCEADD RES..1
(-1550 2025);
FORCEPROP 0 LAST GROUP POWER_FAIR
J 0
(-1675 1975);
DISPLAY 0.638298 (-1675 1975);
PAINT BROWN (-1675 1975);
DISPLAY BOTH (-1675 1975);
FORCEPROP 1 LAST WATTAGE 1/16W
J 2
(-1250 2075);
DISPLAY 0.617021 (-1250 2075);
PAINT SKYBLUE (-1250 2075);
FORCEPROP 1 LAST TOLERANCE 0.1%
J 0
(-1475 2125);
DISPLAY 0.617021 (-1475 2125);
PAINT SKYBLUE (-1475 2125);
FORCEPROP 1 LAST PART_NUMBER G85996-004
J 0
(-1700 2075);
DISPLAY 0.617021 (-1700 2075);
PAINT BLUE (-1700 2075);
FORCEPROP 1 LAST LOCATION RF21
J 0
(-1700 2125);
DISPLAY 0.617021 (-1700 2125);
PAINT AQUA (-1700 2125);
FORCEPROP 1 LASTPIN (-1650 2025) $PN 1
J 0
(-1638 2037);
DISPLAY 0.787234 (-1638 2037);
PAINT ORANGE (-1638 2037);
FORCEPROP 1 LAST VALUE 1.0K
J 2
(-1500 2125);
DISPLAY 0.617021 (-1500 2125);
PAINT SKYBLUE (-1500 2125);
FORCEPROP 1 LASTPIN (-1450 2025) $PN 2
J 0
(-1488 2037);
DISPLAY 0.787234 (-1488 2037);
PAINT ORANGE (-1488 2037);
FORCEPROP 1 LAST PACK_TYPE 0402
J 0
(-1475 2075);
DISPLAY 0.617021 (-1475 2075);
PAINT SKYBLUE (-1475 2075);
FORCEPROP 1 LAST MATERIAL CHIP
J 0
(-1350 2125);
DISPLAY 0.617021 (-1350 2125);
PAINT SKYBLUE (-1350 2125);
FORCEPROP 0 LAST FAIR_SS 064.9090D.M001
J 0
(-1675 1925);
DISPLAY 0.638298 (-1675 1925);
PAINT BROWN (-1675 1925);
DISPLAY BOTH (-1675 1925);
FORCEPROP 1 LAST PATH I16
J 0
(-1600 2175);
DISPLAY 0.978723 (-1600 2175);
PAINT WHITE (-1600 2175);
DISPLAY INVISIBLE (-1600 2175);
FORCEPROP 0 LAST CDS_SEC 1
J 0
(-1250 2175);
PAINT MONO (-1250 2175);
DISPLAY INVISIBLE (-1250 2175);
FORCEPROP 0 LAST CDS_LOCATION RF21
J 0
(-1250 2175);
PAINT MONO (-1250 2175);
DISPLAY INVISIBLE (-1250 2175);
FORCEPROP 2 LAST CDS_LIB mstr_discrete
J 0
(-1550 2025);
PAINT MONO (-1550 2025);
DISPLAY INVISIBLE (-1550 2025);
FORCEPROP 0 LAST ROOM SB
J 0
(-1500 2250);
DISPLAY 1.021277 (-1500 2250);
PAINT ORANGE (-1500 2250);
DISPLAY INVISIBLE (-1500 2250);
FORCEPROP 0 LAST SEC 1
J 0
(-1475 2175);
DISPLAY 0.680851 (-1475 2175);
PAINT MONO (-1475 2175);
DISPLAY INVISIBLE (-1475 2175);
FORCEPROP 2 LAST SEC_TYPE 0402
J 0
(-1600 2225);
DISPLAY 1.021277 (-1600 2225);
PAINT ORANGE (-1600 2225);
DISPLAY INVISIBLE (-1600 2225);
FORCEADD SC22P50V2JN-4GP..1
R 1
(-750 1850);
FORCEPROP 0 LASTPIN (-675 1850) $PN 2
J 0
(-665 1860);
DISPLAY 0.808511 (-665 1860);
PAINT MONO (-665 1860);
FORCEPROP 1 LAST LOCATION CF22
J 0
(-980 1675);
DISPLAY 0.617021 (-980 1675);
PAINT GREEN (-980 1675);
FORCEPROP 2 LAST ATTRIBUTE 22PF
J 0
(-975 1625);
DISPLAY 0.638298 (-975 1625);
PAINT GREEN (-975 1625);
FORCEPROP 2 LAST PACK_SIZE 0402
J 0
(-825 1575);
DISPLAY 0.638298 (-825 1575);
PAINT GREEN (-825 1575);
FORCEPROP 0 LASTPIN (-825 1850) $PN 1
J 2
(-835 1860);
DISPLAY 0.808511 (-835 1860);
PAINT MONO (-835 1860);
FORCEPROP 0 LAST BOM_SS NOPOP
J 0
(-875 1725);
DISPLAY 0.638298 (-875 1725);
PAINT BROWN (-875 1725);
DISPLAY BOTH (-875 1725);
FORCEPROP 2 LAST RATED 50V
J 0
(-700 1625);
DISPLAY 0.638298 (-700 1625);
PAINT GREEN (-700 1625);
FORCEPROP 2 LAST TOLERANCE 5%
J 0
(-825 1625);
DISPLAY 0.638298 (-825 1625);
PAINT GREEN (-825 1625);
FORCEPROP 2 LAST TYPE NPO
J 0
(-975 1575);
DISPLAY 0.638298 (-975 1575);
PAINT GREEN (-975 1575);
FORCEPROP 0 LAST GROUP POWER_FAIR
J 0
(-890 1768);
DISPLAY 0.638298 (-890 1768);
PAINT BROWN (-890 1768);
DISPLAY BOTH (-890 1768);
FORCEPROP 1 LAST VALUE SC22P50V2JN-4GP
J 0
(-825 1675);
DISPLAY 0.617021 (-825 1675);
PAINT GREEN (-825 1675);
FORCEPROP 1 LAST PATH I17
R 1
J 0
(-750 1850);
DISPLAY 0.617021 (-750 1850);
PAINT GREEN (-750 1850);
DISPLAY INVISIBLE (-750 1850);
FORCEPROP 0 LAST CDS_SEC 1
R 1
J 0
(-900 2000);
PAINT MONO (-900 2000);
DISPLAY INVISIBLE (-900 2000);
FORCEPROP 0 LAST $SEC 1
R 1
J 0
(-900 2000);
PAINT MONO (-900 2000);
DISPLAY INVISIBLE (-900 2000);
FORCEPROP 0 LAST CDS_LOCATION CF22
R 1
J 0
(-900 2000);
PAINT MONO (-900 2000);
DISPLAY INVISIBLE (-900 2000);
FORCEPROP 2 LAST CDS_LIB w_hdl
J 0
(-750 1850);
PAINT MONO (-750 1850);
DISPLAY INVISIBLE (-750 1850);
FORCEPROP 1 LAST CDS_LMAN_SYM_OUTLINE -50,25,50,-25
R 1
J 0
(-750 1850);
DISPLAY 0.468085 (-750 1850);
PAINT GREEN (-750 1850);
DISPLAY INVISIBLE (-750 1850);
FORCEPROP 1 LAST PART_NUMBER 78.22034.1FL
R 1
J 0
(-750 1850);
DISPLAY 0.617021 (-750 1850);
PAINT GREEN (-750 1850);
DISPLAY INVISIBLE (-750 1850);
FORCEPROP 1 LAST PACK_TYPE SMD-BCG
R 1
J 0
(-750 1850);
DISPLAY 0.617021 (-750 1850);
PAINT GREEN (-750 1850);
DISPLAY INVISIBLE (-750 1850);
FORCEADD RES..1
(-775 2025);
FORCEPROP 1 LAST PART_NUMBER G85996-004
J 0
(-1025 2075);
DISPLAY 0.617021 (-1025 2075);
PAINT BLUE (-1025 2075);
FORCEPROP 1 LAST PACK_TYPE 0402
J 0
(-775 2075);
DISPLAY 0.617021 (-775 2075);
PAINT SKYBLUE (-775 2075);
FORCEPROP 1 LASTPIN (-675 2025) $PN 2
J 0
(-713 2037);
DISPLAY 0.787234 (-713 2037);
PAINT ORANGE (-713 2037);
FORCEPROP 1 LAST WATTAGE 1/16W
J 2
(-525 2075);
DISPLAY 0.617021 (-525 2075);
PAINT SKYBLUE (-525 2075);
FORCEPROP 1 LAST MATERIAL CHIP
J 0
(-625 2125);
DISPLAY 0.617021 (-625 2125);
PAINT SKYBLUE (-625 2125);
FORCEPROP 1 LAST TOLERANCE 0.1%
J 0
(-750 2125);
DISPLAY 0.617021 (-750 2125);
PAINT SKYBLUE (-750 2125);
FORCEPROP 1 LAST VALUE 1.0K
J 2
(-775 2125);
DISPLAY 0.617021 (-775 2125);
PAINT SKYBLUE (-775 2125);
FORCEPROP 1 LASTPIN (-875 2025) $PN 1
J 0
(-863 2037);
DISPLAY 0.787234 (-863 2037);
PAINT ORANGE (-863 2037);
FORCEPROP 1 LAST LOCATION RF22
J 0
(-1025 2125);
DISPLAY 0.617021 (-1025 2125);
PAINT AQUA (-1025 2125);
FORCEPROP 0 LAST GROUP POWER_FAIR
J 0
(-900 1975);
DISPLAY 0.638298 (-900 1975);
PAINT BROWN (-900 1975);
DISPLAY BOTH (-900 1975);
FORCEPROP 0 LAST BOM_SS NOPOP
J 0
(-900 1925);
DISPLAY 0.638298 (-900 1925);
PAINT BROWN (-900 1925);
DISPLAY BOTH (-900 1925);
FORCEPROP 2 LAST SEC_TYPE 0402
J 0
(-825 2225);
DISPLAY 1.021277 (-825 2225);
PAINT ORANGE (-825 2225);
DISPLAY INVISIBLE (-825 2225);
FORCEPROP 0 LAST SEC 1
J 0
(-700 2175);
DISPLAY 0.680851 (-700 2175);
PAINT MONO (-700 2175);
DISPLAY INVISIBLE (-700 2175);
FORCEPROP 0 LAST ROOM SB
J 0
(-725 2250);
DISPLAY 1.021277 (-725 2250);
PAINT ORANGE (-725 2250);
DISPLAY INVISIBLE (-725 2250);
FORCEPROP 2 LAST CDS_LIB mstr_discrete
J 0
(-775 2025);
PAINT MONO (-775 2025);
DISPLAY INVISIBLE (-775 2025);
FORCEPROP 0 LAST CDS_LOCATION RF22
J 0
(-475 2175);
PAINT MONO (-475 2175);
DISPLAY INVISIBLE (-475 2175);
FORCEPROP 0 LAST CDS_SEC 1
J 0
(-475 2175);
PAINT MONO (-475 2175);
DISPLAY INVISIBLE (-475 2175);
FORCEPROP 1 LAST PATH I18
J 0
(-825 2175);
DISPLAY 0.978723 (-825 2175);
PAINT WHITE (-825 2175);
DISPLAY INVISIBLE (-825 2175);
FORCEADD RES..1
(-550 2350);
FORCEPROP 1 LAST MATERIAL CHIP
J 0
(-450 2375);
DISPLAY 0.617021 (-450 2375);
PAINT SKYBLUE (-450 2375);
FORCEPROP 1 LASTPIN (-450 2350) $PN 2
J 0
(-488 2362);
DISPLAY 0.617021 (-488 2362);
PAINT ORANGE (-488 2362);
FORCEPROP 1 LAST WATTAGE 1/16W
J 2
(-500 2375);
DISPLAY 0.617021 (-500 2375);
PAINT SKYBLUE (-500 2375);
FORCEPROP 1 LAST VALUE 150.0
J 2
(-550 2425);
DISPLAY 0.617021 (-550 2425);
PAINT SKYBLUE (-550 2425);
FORCEPROP 1 LAST PART_NUMBER G21796-009
J 0
(-650 2475);
DISPLAY 0.617021 (-650 2475);
PAINT BLUE (-650 2475);
FORCEPROP 1 LAST LOCATION R1B8
J 0
(-650 2525);
DISPLAY 0.617021 (-650 2525);
PAINT AQUA (-650 2525);
FORCEPROP 1 LAST TOLERANCE 1%
J 0
(-500 2425);
DISPLAY 0.617021 (-500 2425);
PAINT SKYBLUE (-500 2425);
FORCEPROP 1 LAST PACK_TYPE 0402
J 0
(-375 2425);
DISPLAY 0.617021 (-375 2425);
PAINT SKYBLUE (-375 2425);
FORCEPROP 1 LASTPIN (-650 2350) $PN 1
J 0
(-638 2362);
DISPLAY 0.617021 (-638 2362);
PAINT ORANGE (-638 2362);
FORCEPROP 2 LAST CDS_LOCATION R1B8
J 0
(-650 2525);
DISPLAY 0.617021 (-650 2525);
PAINT AQUA (-650 2525);
DISPLAY INVISIBLE (-650 2525);
FORCEPROP 2 LAST ROOM VDDQ_KLM_PWR_VR
J 0
(-650 2575);
DISPLAY 1.361702 (-650 2575);
PAINT ORANGE (-650 2575);
DISPLAY INVISIBLE (-650 2575);
FORCEPROP 2 LAST SEC 1
J 0
(-600 2575);
DISPLAY 0.680851 (-600 2575);
PAINT MONO (-600 2575);
DISPLAY INVISIBLE (-600 2575);
FORCEPROP 2 LAST SEC_TYPE 0402
J 0
(-600 2575);
DISPLAY 1.021277 (-600 2575);
PAINT ORANGE (-600 2575);
DISPLAY INVISIBLE (-600 2575);
FORCEPROP 2 LAST CDS_LIB mstr_discrete
J 0
(-550 2350);
PAINT ORANGE (-550 2350);
DISPLAY INVISIBLE (-550 2350);
FORCEPROP 0 LAST CDS_SEC 1
J 0
(-650 2575);
PAINT MONO (-650 2575);
DISPLAY INVISIBLE (-650 2575);
FORCEPROP 1 LAST PATH I19
J 0
(-600 2500);
DISPLAY 0.978723 (-600 2500);
PAINT WHITE (-600 2500);
DISPLAY INVISIBLE (-600 2500);
FORCEADD OFFPAGE..1
(-2500 775);
FORCEPROP 2 LAST $XR0 191 
J 0
(-2752 775);
DISPLAY 0.638298 (-2752 775);
PAINT MONO (-2752 775);
FORCEPROP 2 LAST ROOM VDDQ_KLM_PWR_VR
J 0
(-3050 850);
DISPLAY 1.361702 (-3050 850);
PAINT ORANGE (-3050 850);
DISPLAY INVISIBLE (-3050 850);
FORCEPROP 2 LAST CDS_LIB mstr_standard
J 0
(-2500 775);
PAINT ORANGE (-2500 775);
DISPLAY INVISIBLE (-2500 775);
FORCEPROP 2 LAST PATH I2
J 0
(-2750 825);
DISPLAY 1.021277 (-2750 825);
PAINT ORANGE (-2750 825);
DISPLAY INVISIBLE (-2750 825);
FORCEPROP 1 LAST OFFPAGE TRUE
J 0
(-2175 650);
DISPLAY 1.170213 (-2175 650);
PAINT GREEN (-2175 650);
DISPLAY INVISIBLE (-2175 650);
FORCEPROP 1 LAST COMMENT_BODY TRUE
J 0
(-2375 675);
DISPLAY 1.170213 (-2375 675);
PAINT GREEN (-2375 675);
DISPLAY INVISIBLE (-2375 675);
FORCEADD PVCCIO_CPU1..1
(-925 3200);
FORCEPROP 3 LASTPIN (-925 3150) SIG_NAME PVCCIO_CPU1\g
J 0
(-915 3160);
DISPLAY 0.659574 (-915 3160);
PAINT MONO (-915 3160);
DISPLAY INVISIBLE (-915 3160);
FORCEPROP 2 LAST CDS_LIB mstr_symbols
J 0
(-925 3200);
PAINT ORANGE (-925 3200);
DISPLAY INVISIBLE (-925 3200);
FORCEPROP 1 LAST VOLTAGE 1.1V
J 0
(-970 3157);
DISPLAY 0.340426 (-970 3157);
PAINT SKYBLUE (-970 3157);
DISPLAY INVISIBLE (-970 3157);
FORCEPROP 1 LAST PATH I21
J 0
(-875 3225);
DISPLAY 0.872340 (-875 3225);
PAINT AQUA (-875 3225);
DISPLAY INVISIBLE (-875 3225);
FORCEPROP 1 LAST BODY_TYPE PLUMBING
J 0
(-970 3157);
DISPLAY 0.340426 (-970 3157);
PAINT GREEN (-970 3157);
DISPLAY INVISIBLE (-970 3157);
FORCEPROP 1 LAST HDL_POWER PVCCIO_CPU1
J 1
(-925 3250);
DISPLAY 0.872340 (-925 3250);
PAINT GREEN (-925 3250);
DISPLAY INVISIBLE (-925 3250);
FORCEADD GND..1
(-225 -675);
FORCEPROP 3 LASTPIN (-225 -625) SIG_NAME GND\g
J 0
(-215 -615);
DISPLAY 0.659574 (-215 -615);
PAINT MONO (-215 -615);
DISPLAY INVISIBLE (-215 -615);
FORCEPROP 2 LAST ROOM VDDQ_KLM_PWR_VR
J 0
(-800 -600);
DISPLAY 1.361702 (-800 -600);
PAINT ORANGE (-800 -600);
DISPLAY INVISIBLE (-800 -600);
FORCEPROP 1 LAST SIZE 1B
J 0
(-150 -725);
DISPLAY 1.170213 (-150 -725);
PAINT AQUA (-150 -725);
DISPLAY INVISIBLE (-150 -725);
FORCEPROP 2 LAST CDS_LIB mstr_symbols
J 0
(-225 -675);
PAINT ORANGE (-225 -675);
DISPLAY INVISIBLE (-225 -675);
FORCEPROP 1 LAST VOLTAGE 0
J 0
(-225 -675);
PAINT SKYBLUE (-225 -675);
DISPLAY INVISIBLE (-225 -675);
FORCEPROP 1 LAST PATH I22
J 0
(-150 -675);
DISPLAY 0.872340 (-150 -675);
PAINT AQUA (-150 -675);
DISPLAY INVISIBLE (-150 -675);
FORCEPROP 1 LAST BODY_TYPE PLUMBING
J 0
(-270 -718);
DISPLAY 0.340426 (-270 -718);
PAINT GREEN (-270 -718);
DISPLAY INVISIBLE (-270 -718);
FORCEPROP 1 LAST HDL_POWER GND
J 0
(-225 -525);
DISPLAY 1.170213 (-225 -525);
PAINT GREEN (-225 -525);
DISPLAY INVISIBLE (-225 -525);
FORCEADD CAP..1
R 2
(-225 25);
FORCEPROP 1 LASTPIN (-225 125) $PN 1
J 2
(-235 105);
DISPLAY 0.617021 (-235 105);
PAINT ORANGE (-235 105);
FORCEPROP 1 LASTPIN (-225 -75) $PN 2
J 2
(-235 -95);
DISPLAY 0.617021 (-235 -95);
PAINT ORANGE (-235 -95);
FORCEPROP 1 LAST VOLTAGE 50V
J 2
(-275 25);
DISPLAY 0.617021 (-275 25);
PAINT SKYBLUE (-275 25);
FORCEPROP 1 LAST MATERIAL X7R
J 2
(-400 25);
DISPLAY 0.617021 (-400 25);
PAINT SKYBLUE (-400 25);
FORCEPROP 1 LAST TOLERANCE 10%
J 2
(-450 75);
DISPLAY 0.617021 (-450 75);
PAINT SKYBLUE (-450 75);
FORCEPROP 1 LAST PACK_TYPE 0402LF
J 2
(-275 -75);
DISPLAY 0.617021 (-275 -75);
PAINT SKYBLUE (-275 -75);
FORCEPROP 1 LAST PART_NUMBER A36096-050
J 2
(-275 -25);
DISPLAY 0.617021 (-275 -25);
PAINT BLUE (-275 -25);
FORCEPROP 1 LAST LOCATION C1B11
J 2
(-275 125);
DISPLAY 0.617021 (-275 125);
PAINT AQUA (-275 125);
FORCEPROP 1 LAST VALUE 220PF
J 2
(-275 75);
DISPLAY 0.617021 (-275 75);
PAINT SKYBLUE (-275 75);
FORCEPROP 2 LAST SEC_TYPE 0402LF
J 2
(-275 250);
DISPLAY 1.021277 (-275 250);
PAINT ORANGE (-275 250);
DISPLAY INVISIBLE (-275 250);
FORCEPROP 2 LAST SEC 1
J 2
(-275 250);
DISPLAY 0.680851 (-275 250);
PAINT MONO (-275 250);
DISPLAY INVISIBLE (-275 250);
FORCEPROP 2 LAST CDS_LOCATION C1B11
J 2
(-275 125);
DISPLAY 0.617021 (-275 125);
PAINT AQUA (-275 125);
DISPLAY INVISIBLE (-275 125);
FORCEPROP 2 LAST ROOM VDDQ_KLM_PWR_VR
J 2
(-275 175);
DISPLAY 1.361702 (-275 175);
PAINT ORANGE (-275 175);
DISPLAY INVISIBLE (-275 175);
FORCEPROP 2 LAST CDS_LIB mstr_discrete
J 2
(-225 25);
PAINT ORANGE (-225 25);
DISPLAY INVISIBLE (-225 25);
FORCEPROP 0 LAST CDS_SEC 1
J 0
(-275 175);
PAINT MONO (-275 175);
DISPLAY INVISIBLE (-275 175);
FORCEPROP 1 LAST PATH I23
J 2
(-275 175);
DISPLAY 0.978723 (-275 175);
PAINT WHITE (-275 175);
DISPLAY INVISIBLE (-275 175);
FORCEADD GND..1
(3100 -750);
FORCEPROP 3 LASTPIN (3100 -700) SIG_NAME GND\g
J 0
(3110 -690);
DISPLAY 0.659574 (3110 -690);
PAINT MONO (3110 -690);
DISPLAY INVISIBLE (3110 -690);
FORCEPROP 2 LAST ROOM VDDQ_KLM_PWR_VR
J 0
(2525 -675);
DISPLAY 1.361702 (2525 -675);
PAINT ORANGE (2525 -675);
DISPLAY INVISIBLE (2525 -675);
FORCEPROP 1 LAST VOLTAGE 0
J 0
(3100 -750);
PAINT SKYBLUE (3100 -750);
DISPLAY INVISIBLE (3100 -750);
FORCEPROP 2 LAST CDS_LIB mstr_symbols
J 0
(3100 -750);
PAINT ORANGE (3100 -750);
DISPLAY INVISIBLE (3100 -750);
FORCEPROP 1 LAST SIZE 1B
J 0
(3175 -800);
DISPLAY 1.170213 (3175 -800);
PAINT AQUA (3175 -800);
DISPLAY INVISIBLE (3175 -800);
FORCEPROP 1 LAST PATH I24
J 0
(3175 -750);
DISPLAY 0.872340 (3175 -750);
PAINT AQUA (3175 -750);
DISPLAY INVISIBLE (3175 -750);
FORCEPROP 1 LAST BODY_TYPE PLUMBING
J 0
(3055 -793);
DISPLAY 0.340426 (3055 -793);
PAINT GREEN (3055 -793);
DISPLAY INVISIBLE (3055 -793);
FORCEPROP 1 LAST HDL_POWER GND
J 0
(3100 -600);
DISPLAY 1.170213 (3100 -600);
PAINT GREEN (3100 -600);
DISPLAY INVISIBLE (3100 -600);
FORCEADD GND..1
(3500 -750);
FORCEPROP 3 LASTPIN (3500 -700) SIG_NAME GND\g
J 0
(3510 -690);
DISPLAY 0.659574 (3510 -690);
PAINT MONO (3510 -690);
DISPLAY INVISIBLE (3510 -690);
FORCEPROP 1 LAST VOLTAGE 0
J 0
(3500 -750);
PAINT SKYBLUE (3500 -750);
DISPLAY INVISIBLE (3500 -750);
FORCEPROP 1 LAST SIZE 1B
J 0
(3575 -800);
DISPLAY 1.170213 (3575 -800);
PAINT AQUA (3575 -800);
DISPLAY INVISIBLE (3575 -800);
FORCEPROP 2 LAST CDS_LIB mstr_symbols
J 0
(3500 -750);
PAINT ORANGE (3500 -750);
DISPLAY INVISIBLE (3500 -750);
FORCEPROP 2 LAST ROOM VDDQ_KLM_PWR_VR
J 0
(2925 -675);
DISPLAY 1.361702 (2925 -675);
PAINT ORANGE (2925 -675);
DISPLAY INVISIBLE (2925 -675);
FORCEPROP 1 LAST PATH I25
J 0
(3575 -750);
DISPLAY 0.872340 (3575 -750);
PAINT AQUA (3575 -750);
DISPLAY INVISIBLE (3575 -750);
FORCEPROP 1 LAST BODY_TYPE PLUMBING
J 0
(3455 -793);
DISPLAY 0.340426 (3455 -793);
PAINT GREEN (3455 -793);
DISPLAY INVISIBLE (3455 -793);
FORCEPROP 1 LAST HDL_POWER GND
J 0
(3500 -600);
DISPLAY 1.170213 (3500 -600);
PAINT GREEN (3500 -600);
DISPLAY INVISIBLE (3500 -600);
FORCEADD GND..1
(-50 -850);
FORCEPROP 3 LASTPIN (-50 -800) SIG_NAME GND\g
J 0
(-40 -790);
DISPLAY 0.659574 (-40 -790);
PAINT MONO (-40 -790);
DISPLAY INVISIBLE (-40 -790);
FORCEPROP 1 LAST PATH I26
J 0
(25 -850);
DISPLAY 0.872340 (25 -850);
PAINT AQUA (25 -850);
DISPLAY INVISIBLE (25 -850);
FORCEPROP 2 LAST CDS_LIB mstr_symbols
J 0
(-50 -850);
PAINT ORANGE (-50 -850);
DISPLAY INVISIBLE (-50 -850);
FORCEPROP 1 LAST VOLTAGE 0
J 0
(-50 -850);
PAINT SKYBLUE (-50 -850);
DISPLAY INVISIBLE (-50 -850);
FORCEPROP 1 LAST SIZE 1B
J 0
(25 -900);
DISPLAY 1.170213 (25 -900);
PAINT AQUA (25 -900);
DISPLAY INVISIBLE (25 -900);
FORCEPROP 2 LAST ROOM VDDQ_KLM_PWR_VR
J 0
(-625 -775);
DISPLAY 1.361702 (-625 -775);
PAINT ORANGE (-625 -775);
DISPLAY INVISIBLE (-625 -775);
FORCEPROP 1 LAST BODY_TYPE PLUMBING
J 0
(-95 -893);
DISPLAY 0.340426 (-95 -893);
PAINT GREEN (-95 -893);
DISPLAY INVISIBLE (-95 -893);
FORCEPROP 1 LAST HDL_POWER GND
J 0
(-50 -700);
DISPLAY 1.170213 (-50 -700);
PAINT GREEN (-50 -700);
DISPLAY INVISIBLE (-50 -700);
FORCEADD GND..1
(-150 125);
FORCEPROP 3 LASTPIN (-150 175) SIG_NAME GND\g
J 0
(-140 185);
DISPLAY 0.659574 (-140 185);
PAINT MONO (-140 185);
DISPLAY INVISIBLE (-140 185);
FORCEPROP 2 LAST ROOM VDDQ_KLM_PWR_VR
J 0
(-725 200);
DISPLAY 1.361702 (-725 200);
PAINT ORANGE (-725 200);
DISPLAY INVISIBLE (-725 200);
FORCEPROP 1 LAST VOLTAGE 0
J 0
(-150 125);
PAINT SKYBLUE (-150 125);
DISPLAY INVISIBLE (-150 125);
FORCEPROP 2 LAST CDS_LIB mstr_symbols
J 0
(-150 125);
PAINT ORANGE (-150 125);
DISPLAY INVISIBLE (-150 125);
FORCEPROP 1 LAST SIZE 1B
J 0
(-75 75);
DISPLAY 1.170213 (-75 75);
PAINT AQUA (-75 75);
DISPLAY INVISIBLE (-75 75);
FORCEPROP 1 LAST PATH I28
J 0
(-75 125);
DISPLAY 0.872340 (-75 125);
PAINT AQUA (-75 125);
DISPLAY INVISIBLE (-75 125);
FORCEPROP 1 LAST BODY_TYPE PLUMBING
J 0
(-195 82);
DISPLAY 0.340426 (-195 82);
PAINT GREEN (-195 82);
DISPLAY INVISIBLE (-195 82);
FORCEPROP 1 LAST HDL_POWER GND
J 0
(-150 275);
DISPLAY 1.170213 (-150 275);
PAINT GREEN (-150 275);
DISPLAY INVISIBLE (-150 275);
FORCEADD GND..1
(325 -850);
FORCEPROP 3 LASTPIN (325 -800) SIG_NAME GND\g
J 0
(335 -790);
DISPLAY 0.659574 (335 -790);
PAINT MONO (335 -790);
DISPLAY INVISIBLE (335 -790);
FORCEPROP 1 LAST PATH I29
J 0
(400 -850);
DISPLAY 0.872340 (400 -850);
PAINT AQUA (400 -850);
DISPLAY INVISIBLE (400 -850);
FORCEPROP 2 LAST CDS_LIB mstr_symbols
J 0
(325 -850);
PAINT ORANGE (325 -850);
DISPLAY INVISIBLE (325 -850);
FORCEPROP 1 LAST VOLTAGE 0
J 0
(325 -850);
PAINT SKYBLUE (325 -850);
DISPLAY INVISIBLE (325 -850);
FORCEPROP 1 LAST SIZE 1B
J 0
(400 -900);
DISPLAY 1.170213 (400 -900);
PAINT AQUA (400 -900);
DISPLAY INVISIBLE (400 -900);
FORCEPROP 2 LAST ROOM VDDQ_KLM_PWR_VR
J 0
(-250 -775);
DISPLAY 1.361702 (-250 -775);
PAINT ORANGE (-250 -775);
DISPLAY INVISIBLE (-250 -775);
FORCEPROP 1 LAST BODY_TYPE PLUMBING
J 0
(280 -893);
DISPLAY 0.340426 (280 -893);
PAINT GREEN (280 -893);
DISPLAY INVISIBLE (280 -893);
FORCEPROP 1 LAST HDL_POWER GND
J 0
(325 -700);
DISPLAY 1.170213 (325 -700);
PAINT GREEN (325 -700);
DISPLAY INVISIBLE (325 -700);
FORCEADD OFFPAGE..1
(-2500 475);
FORCEPROP 2 LAST $XR0 228 
J 0
(-2752 475);
DISPLAY 0.638298 (-2752 475);
PAINT MONO (-2752 475);
FORCEPROP 2 LAST ROOM VDDQ_KLM_PWR_VR
J 0
(-3050 550);
DISPLAY 1.361702 (-3050 550);
PAINT ORANGE (-3050 550);
DISPLAY INVISIBLE (-3050 550);
FORCEPROP 2 LAST CDS_LIB mstr_standard
J 0
(-2500 475);
PAINT ORANGE (-2500 475);
DISPLAY INVISIBLE (-2500 475);
FORCEPROP 2 LAST PATH I3
J 0
(-2750 525);
DISPLAY 1.021277 (-2750 525);
PAINT ORANGE (-2750 525);
DISPLAY INVISIBLE (-2750 525);
FORCEPROP 1 LAST OFFPAGE TRUE
J 0
(-2175 350);
DISPLAY 1.170213 (-2175 350);
PAINT GREEN (-2175 350);
DISPLAY INVISIBLE (-2175 350);
FORCEPROP 1 LAST COMMENT_BODY TRUE
J 0
(-2375 375);
DISPLAY 1.170213 (-2375 375);
PAINT GREEN (-2375 375);
DISPLAY INVISIBLE (-2375 375);
FORCEADD GND..1
(1750 100);
FORCEPROP 3 LASTPIN (1750 150) SIG_NAME GND\g
J 0
(1760 160);
DISPLAY 0.659574 (1760 160);
PAINT MONO (1760 160);
DISPLAY INVISIBLE (1760 160);
FORCEPROP 2 LAST ROOM VDDQ_KLM_PWR_VR
J 0
(1175 175);
DISPLAY 1.361702 (1175 175);
PAINT ORANGE (1175 175);
DISPLAY INVISIBLE (1175 175);
FORCEPROP 2 LAST CDS_LIB mstr_symbols
J 0
(1750 100);
PAINT ORANGE (1750 100);
DISPLAY INVISIBLE (1750 100);
FORCEPROP 1 LAST VOLTAGE 0
J 0
(1750 100);
PAINT SKYBLUE (1750 100);
DISPLAY INVISIBLE (1750 100);
FORCEPROP 1 LAST SIZE 1B
J 0
(1825 50);
DISPLAY 1.170213 (1825 50);
PAINT AQUA (1825 50);
DISPLAY INVISIBLE (1825 50);
FORCEPROP 1 LAST PATH I31
J 0
(1825 100);
DISPLAY 0.872340 (1825 100);
PAINT AQUA (1825 100);
DISPLAY INVISIBLE (1825 100);
FORCEPROP 1 LAST BODY_TYPE PLUMBING
J 0
(1705 57);
DISPLAY 0.340426 (1705 57);
PAINT GREEN (1705 57);
DISPLAY INVISIBLE (1705 57);
FORCEPROP 1 LAST HDL_POWER GND
J 0
(1750 250);
DISPLAY 1.170213 (1750 250);
PAINT GREEN (1750 250);
DISPLAY INVISIBLE (1750 250);
FORCEADD CAP_A..1
(675 2375);
FORCEPROP 1 LAST VALUE 0.1UF
J 0
(725 2425);
DISPLAY 0.617021 (725 2425);
PAINT SKYBLUE (725 2425);
FORCEPROP 1 LASTPIN (675 2275) $PN 2
J 0
(685 2255);
DISPLAY 0.617021 (685 2255);
PAINT ORANGE (685 2255);
FORCEPROP 1 LAST LOCATION C1B5
J 0
(725 2475);
DISPLAY 0.617021 (725 2475);
PAINT AQUA (725 2475);
FORCEPROP 1 LAST PACK_TYPE 0402V
J 0
(725 2175);
DISPLAY 0.617021 (725 2175);
PAINT SKYBLUE (725 2175);
FORCEPROP 1 LASTPIN (675 2475) $PN 1
J 0
(685 2455);
DISPLAY 0.617021 (685 2455);
PAINT ORANGE (685 2455);
FORCEPROP 1 LAST VOLTAGE 16V
J 0
(725 2375);
DISPLAY 0.617021 (725 2375);
PAINT SKYBLUE (725 2375);
FORCEPROP 1 LAST MATERIAL X7R
J 0
(725 2275);
DISPLAY 0.617021 (725 2275);
PAINT SKYBLUE (725 2275);
FORCEPROP 1 LAST TOLERANCE 10%
J 0
(725 2325);
DISPLAY 0.617021 (725 2325);
PAINT SKYBLUE (725 2325);
FORCEPROP 1 LAST PART_NUMBER A36096-030
J 0
(725 2225);
DISPLAY 0.617021 (725 2225);
PAINT BLUE (725 2225);
FORCEPROP 2 LAST CDS_LIB dev_discrete
J 0
(675 2375);
PAINT ORANGE (675 2375);
DISPLAY INVISIBLE (675 2375);
FORCEPROP 2 LAST CDS_SEC 1
J 0
(725 2525);
PAINT ORANGE (725 2525);
DISPLAY INVISIBLE (725 2525);
FORCEPROP 2 LAST ROOM VDDQ_KLM_PWR_VR
J 0
(725 2525);
DISPLAY 1.361702 (725 2525);
PAINT ORANGE (725 2525);
DISPLAY INVISIBLE (725 2525);
FORCEPROP 2 LAST CDS_LOCATION C1B5
J 0
(725 2475);
DISPLAY 0.617021 (725 2475);
PAINT AQUA (725 2475);
DISPLAY INVISIBLE (725 2475);
FORCEPROP 2 LAST SEC 1
J 0
(725 2600);
DISPLAY 0.680851 (725 2600);
PAINT MONO (725 2600);
DISPLAY INVISIBLE (725 2600);
FORCEPROP 2 LAST SEC_TYPE 0402V
J 0
(725 2600);
DISPLAY 1.021277 (725 2600);
PAINT ORANGE (725 2600);
DISPLAY INVISIBLE (725 2600);
FORCEPROP 1 LAST PATH I32
J 0
(725 2525);
DISPLAY 0.978723 (725 2525);
PAINT WHITE (725 2525);
DISPLAY INVISIBLE (725 2525);
FORCEADD GND..1
(675 2175);
FORCEPROP 3 LASTPIN (675 2225) SIG_NAME GND\g
J 0
(685 2235);
DISPLAY 0.659574 (685 2235);
PAINT MONO (685 2235);
DISPLAY INVISIBLE (685 2235);
FORCEPROP 2 LAST ROOM VDDQ_KLM_PWR_VR
J 0
(100 2250);
DISPLAY 1.361702 (100 2250);
PAINT ORANGE (100 2250);
DISPLAY INVISIBLE (100 2250);
FORCEPROP 1 LAST VOLTAGE 0
J 0
(675 2175);
PAINT SKYBLUE (675 2175);
DISPLAY INVISIBLE (675 2175);
FORCEPROP 2 LAST CDS_LIB mstr_symbols
J 0
(675 2175);
PAINT ORANGE (675 2175);
DISPLAY INVISIBLE (675 2175);
FORCEPROP 1 LAST SIZE 1B
J 0
(750 2125);
DISPLAY 1.170213 (750 2125);
PAINT AQUA (750 2125);
DISPLAY INVISIBLE (750 2125);
FORCEPROP 1 LAST PATH I33
J 0
(750 2175);
DISPLAY 0.872340 (750 2175);
PAINT AQUA (750 2175);
DISPLAY INVISIBLE (750 2175);
FORCEPROP 1 LAST BODY_TYPE PLUMBING
J 0
(630 2132);
DISPLAY 0.340426 (630 2132);
PAINT GREEN (630 2132);
DISPLAY INVISIBLE (630 2132);
FORCEPROP 1 LAST HDL_POWER GND
J 0
(675 2325);
DISPLAY 1.170213 (675 2325);
PAINT GREEN (675 2325);
DISPLAY INVISIBLE (675 2325);
FORCEADD RES..2
(-175 2850);
FORCEPROP 1 LAST WATTAGE 1/16W
J 0
(-135 2825);
DISPLAY 0.617021 (-135 2825);
PAINT SKYBLUE (-135 2825);
FORCEPROP 1 LAST MATERIAL EMPTY
J 0
(-135 2775);
DISPLAY 0.617021 (-135 2775);
PAINT RED (-135 2775);
FORCEPROP 1 LASTPIN (-175 2950) $PN 1
J 0
(-170 2912);
DISPLAY 0.617021 (-170 2912);
PAINT ORANGE (-170 2912);
FORCEPROP 1 LAST VALUE 100.0K
J 0
(-130 2925);
DISPLAY 0.617021 (-130 2925);
PAINT SKYBLUE (-130 2925);
FORCEPROP 1 LAST PACK_TYPE 0402
J 0
(-135 2675);
DISPLAY 0.617021 (-135 2675);
PAINT SKYBLUE (-135 2675);
FORCEPROP 1 LASTPIN (-175 2750) $PN 2
J 0
(-170 2760);
DISPLAY 0.617021 (-170 2760);
PAINT ORANGE (-170 2760);
FORCEPROP 1 LAST TOLERANCE 1%
J 0
(-130 2875);
DISPLAY 0.617021 (-130 2875);
PAINT SKYBLUE (-130 2875);
FORCEPROP 1 LAST PART_NUMBER G21796-010
J 0
(-135 2725);
DISPLAY 0.617021 (-135 2725);
PAINT BLUE (-135 2725);
FORCEPROP 1 LAST LOCATION R9M5
J 0
(-130 2975);
DISPLAY 0.617021 (-130 2975);
PAINT AQUA (-130 2975);
FORCEPROP 2 LAST CDS_LIB mstr_discrete
J 0
(-175 2850);
PAINT ORANGE (-175 2850);
DISPLAY INVISIBLE (-175 2850);
FORCEPROP 2 LAST CDS_LOCATION R9M5
J 0
(-130 2975);
DISPLAY 0.617021 (-130 2975);
PAINT AQUA (-130 2975);
DISPLAY INVISIBLE (-130 2975);
FORCEPROP 0 LAST ROOM BMC
J 0
(-125 3075);
DISPLAY 0.617021 (-125 3075);
PAINT ORANGE (-125 3075);
DISPLAY INVISIBLE (-125 3075);
FORCEPROP 2 LAST SEC 1
J 0
(-125 3075);
PAINT MONO (-125 3075);
DISPLAY INVISIBLE (-125 3075);
FORCEPROP 2 LAST SEC_TYPE 0402
J 0
(-125 3075);
DISPLAY 1.021277 (-125 3075);
PAINT ORANGE (-125 3075);
DISPLAY INVISIBLE (-125 3075);
FORCEPROP 0 LAST BOM_COST SM_CONTROLLER
J 0
(-125 3175);
DISPLAY 1.021277 (-125 3175);
PAINT ORANGE (-125 3175);
DISPLAY INVISIBLE (-125 3175);
FORCEPROP 0 LAST CDS_SEC 1
J 0
(-125 3025);
PAINT MONO (-125 3025);
DISPLAY INVISIBLE (-125 3025);
FORCEPROP 1 LAST PATH I34
J 0
(-125 3025);
DISPLAY 0.978723 (-125 3025);
PAINT WHITE (-125 3025);
DISPLAY INVISIBLE (-125 3025);
FORCEADD P3V3_STBY..1
(250 3200);
FORCEPROP 3 LASTPIN (250 3150) SIG_NAME P3V3_STBY\g
J 0
(260 3160);
DISPLAY 0.659574 (260 3160);
PAINT MONO (260 3160);
DISPLAY INVISIBLE (260 3160);
FORCEPROP 1 LAST SIZE 1B
J 0
(295 3222);
DISPLAY 0.340426 (295 3222);
PAINT GREEN (295 3222);
DISPLAY INVISIBLE (295 3222);
FORCEPROP 1 LAST VOLTAGE 3.3V
J 0
(205 3157);
DISPLAY 0.340426 (205 3157);
PAINT SKYBLUE (205 3157);
DISPLAY INVISIBLE (205 3157);
FORCEPROP 2 LAST CDS_LIB mstr_symbols
J 0
(250 3200);
PAINT ORANGE (250 3200);
DISPLAY INVISIBLE (250 3200);
FORCEPROP 1 LAST PATH I35
J 0
(295 3202);
DISPLAY 0.340426 (295 3202);
PAINT GREEN (295 3202);
DISPLAY INVISIBLE (295 3202);
FORCEPROP 1 LAST BODY_TYPE PLUMBING
J 0
(205 3157);
DISPLAY 0.340426 (205 3157);
PAINT GREEN (205 3157);
DISPLAY INVISIBLE (205 3157);
FORCEPROP 1 LAST HDL_POWER P3V3_STBY
J 0
(-50 3075);
DISPLAY 0.872340 (-50 3075);
PAINT ORANGE (-50 3075);
DISPLAY INVISIBLE (-50 3075);
FORCEADD RES..2
(575 2825);
FORCEPROP 1 LAST MATERIAL CHIP
J 0
(615 2750);
DISPLAY 0.617021 (615 2750);
PAINT SKYBLUE (615 2750);
FORCEPROP 1 LAST WATTAGE 1/16W
J 0
(615 2800);
DISPLAY 0.617021 (615 2800);
PAINT SKYBLUE (615 2800);
FORCEPROP 1 LAST PACK_TYPE 0402
J 0
(615 2650);
DISPLAY 0.617021 (615 2650);
PAINT SKYBLUE (615 2650);
FORCEPROP 1 LASTPIN (575 2925) $PN 1
J 0
(580 2887);
DISPLAY 0.617021 (580 2887);
PAINT ORANGE (580 2887);
FORCEPROP 1 LASTPIN (575 2725) $PN 2
J 0
(580 2735);
DISPLAY 0.617021 (580 2735);
PAINT ORANGE (580 2735);
FORCEPROP 1 LAST LOCATION R9M3
J 0
(620 2950);
DISPLAY 0.617021 (620 2950);
PAINT AQUA (620 2950);
FORCEPROP 1 LAST TOLERANCE 5%
J 0
(620 2850);
DISPLAY 0.617021 (620 2850);
PAINT SKYBLUE (620 2850);
FORCEPROP 1 LAST VALUE 0.0
J 0
(620 2900);
DISPLAY 0.617021 (620 2900);
PAINT SKYBLUE (620 2900);
FORCEPROP 1 LAST PART_NUMBER G21497-005
J 0
(615 2700);
DISPLAY 0.617021 (615 2700);
PAINT BLUE (615 2700);
FORCEPROP 2 LAST CDS_LIB mstr_discrete
J 0
(575 2825);
PAINT ORANGE (575 2825);
DISPLAY INVISIBLE (575 2825);
FORCEPROP 2 LAST ROOM VDDQ_KLM_PWR_VR
J 0
(625 3000);
DISPLAY 1.361702 (625 3000);
PAINT ORANGE (625 3000);
DISPLAY INVISIBLE (625 3000);
FORCEPROP 2 LAST CDS_LOCATION R9M3
J 0
(620 2950);
DISPLAY 0.617021 (620 2950);
PAINT AQUA (620 2950);
DISPLAY INVISIBLE (620 2950);
FORCEPROP 2 LAST SEC_TYPE 0402
J 0
(625 3075);
DISPLAY 1.021277 (625 3075);
PAINT ORANGE (625 3075);
DISPLAY INVISIBLE (625 3075);
FORCEPROP 2 LAST SEC 1
J 0
(625 3075);
DISPLAY 0.680851 (625 3075);
PAINT MONO (625 3075);
DISPLAY INVISIBLE (625 3075);
FORCEPROP 0 LAST CDS_SEC 1
J 0
(625 3000);
PAINT MONO (625 3000);
DISPLAY INVISIBLE (625 3000);
FORCEPROP 1 LAST PATH I36
J 0
(625 3000);
DISPLAY 0.978723 (625 3000);
PAINT WHITE (625 3000);
DISPLAY INVISIBLE (625 3000);
FORCEADD GND..1
(1275 2175);
FORCEPROP 3 LASTPIN (1275 2225) SIG_NAME GND\g
J 0
(1285 2235);
DISPLAY 0.659574 (1285 2235);
PAINT MONO (1285 2235);
DISPLAY INVISIBLE (1285 2235);
FORCEPROP 2 LAST ROOM VDDQ_KLM_PWR_VR
J 0
(700 2250);
DISPLAY 1.361702 (700 2250);
PAINT ORANGE (700 2250);
DISPLAY INVISIBLE (700 2250);
FORCEPROP 2 LAST CDS_LIB mstr_symbols
J 0
(1275 2175);
PAINT ORANGE (1275 2175);
DISPLAY INVISIBLE (1275 2175);
FORCEPROP 1 LAST VOLTAGE 0
J 0
(1275 2175);
PAINT SKYBLUE (1275 2175);
DISPLAY INVISIBLE (1275 2175);
FORCEPROP 1 LAST SIZE 1B
J 0
(1350 2125);
DISPLAY 1.170213 (1350 2125);
PAINT AQUA (1350 2125);
DISPLAY INVISIBLE (1350 2125);
FORCEPROP 1 LAST PATH I37
J 0
(1350 2175);
DISPLAY 0.872340 (1350 2175);
PAINT AQUA (1350 2175);
DISPLAY INVISIBLE (1350 2175);
FORCEPROP 1 LAST BODY_TYPE PLUMBING
J 0
(1230 2132);
DISPLAY 0.340426 (1230 2132);
PAINT GREEN (1230 2132);
DISPLAY INVISIBLE (1230 2132);
FORCEPROP 1 LAST HDL_POWER GND
J 0
(1275 2325);
DISPLAY 1.170213 (1275 2325);
PAINT GREEN (1275 2325);
DISPLAY INVISIBLE (1275 2325);
FORCEADD CAP_A..1
(1275 2375);
FORCEPROP 1 LASTPIN (1275 2275) $PN 2
J 0
(1285 2255);
DISPLAY 0.787234 (1285 2255);
PAINT ORANGE (1285 2255);
FORCEPROP 1 LAST PART_NUMBER D97712-004
J 0
(1325 2225);
DISPLAY 0.617021 (1325 2225);
PAINT BLUE (1325 2225);
FORCEPROP 1 LAST PACK_TYPE 0402V
J 0
(1325 2175);
DISPLAY 0.617021 (1325 2175);
PAINT SKYBLUE (1325 2175);
FORCEPROP 1 LASTPIN (1275 2475) $PN 1
J 0
(1285 2455);
DISPLAY 0.787234 (1285 2455);
PAINT ORANGE (1285 2455);
FORCEPROP 1 LAST LOCATION C1B6
J 0
(1325 2475);
DISPLAY 0.617021 (1325 2475);
PAINT AQUA (1325 2475);
FORCEPROP 1 LAST VALUE 1.0UF
J 0
(1325 2425);
DISPLAY 0.617021 (1325 2425);
PAINT SKYBLUE (1325 2425);
FORCEPROP 1 LAST MATERIAL X6S
J 0
(1325 2275);
DISPLAY 0.617021 (1325 2275);
PAINT SKYBLUE (1325 2275);
FORCEPROP 1 LAST VOLTAGE 6.3V
J 0
(1325 2375);
DISPLAY 0.617021 (1325 2375);
PAINT SKYBLUE (1325 2375);
FORCEPROP 1 LAST TOLERANCE 10%
J 0
(1325 2325);
DISPLAY 0.617021 (1325 2325);
PAINT SKYBLUE (1325 2325);
FORCEPROP 2 LAST SEC_TYPE 0402V
J 0
(1325 2575);
DISPLAY 1.021277 (1325 2575);
PAINT ORANGE (1325 2575);
DISPLAY INVISIBLE (1325 2575);
FORCEPROP 2 LAST SEC 1
J 0
(1325 2575);
DISPLAY 0.680851 (1325 2575);
PAINT MONO (1325 2575);
DISPLAY INVISIBLE (1325 2575);
FORCEPROP 2 LAST CDS_LIB dev_discrete
J 0
(1275 2375);
PAINT ORANGE (1275 2375);
DISPLAY INVISIBLE (1275 2375);
FORCEPROP 2 LAST ROOM VDDQ_KLM_PWR_VR
J 0
(1325 2525);
DISPLAY 1.361702 (1325 2525);
PAINT ORANGE (1325 2525);
DISPLAY INVISIBLE (1325 2525);
FORCEPROP 2 LAST CDS_LOCATION C1B6
J 0
(1325 2475);
DISPLAY 0.617021 (1325 2475);
PAINT AQUA (1325 2475);
DISPLAY INVISIBLE (1325 2475);
FORCEPROP 0 LAST CDS_SEC 1
J 0
(1325 2525);
PAINT MONO (1325 2525);
DISPLAY INVISIBLE (1325 2525);
FORCEPROP 1 LAST PATH I38
J 0
(1325 2525);
DISPLAY 0.978723 (1325 2525);
PAINT WHITE (1325 2525);
DISPLAY INVISIBLE (1325 2525);
FORCEADD GND..1
(2650 0);
FORCEPROP 3 LASTPIN (2650 50) SIG_NAME GND\g
J 0
(2660 60);
DISPLAY 0.659574 (2660 60);
PAINT MONO (2660 60);
DISPLAY INVISIBLE (2660 60);
FORCEPROP 2 LAST ROOM VDDQ_KLM_PWR_VR
J 0
(2075 75);
DISPLAY 1.361702 (2075 75);
PAINT ORANGE (2075 75);
DISPLAY INVISIBLE (2075 75);
FORCEPROP 1 LAST VOLTAGE 0
J 0
(2650 0);
PAINT SKYBLUE (2650 0);
DISPLAY INVISIBLE (2650 0);
FORCEPROP 2 LAST CDS_LIB mstr_symbols
J 0
(2650 0);
PAINT MONO (2650 0);
DISPLAY INVISIBLE (2650 0);
FORCEPROP 1 LAST SIZE 1B
J 0
(2725 -50);
DISPLAY 1.170213 (2725 -50);
PAINT AQUA (2725 -50);
DISPLAY INVISIBLE (2725 -50);
FORCEPROP 1 LAST PATH I39
J 0
(2725 0);
DISPLAY 0.872340 (2725 0);
PAINT AQUA (2725 0);
DISPLAY INVISIBLE (2725 0);
FORCEPROP 1 LAST BODY_TYPE PLUMBING
J 0
(2605 -43);
DISPLAY 0.340426 (2605 -43);
PAINT GREEN (2605 -43);
DISPLAY INVISIBLE (2605 -43);
FORCEPROP 1 LAST HDL_POWER GND
J 0
(2650 150);
DISPLAY 1.170213 (2650 150);
PAINT GREEN (2650 150);
DISPLAY INVISIBLE (2650 150);
FORCEADD OFFPAGE..1
(-2500 1225);
FORCEPROP 2 LAST $XR0 197 
J 0
(-2752 1225);
DISPLAY 0.638298 (-2752 1225);
PAINT MONO (-2752 1225);
FORCEPROP 2 LAST CDS_LIB mstr_standard
J 0
(-2500 1225);
PAINT ORANGE (-2500 1225);
DISPLAY INVISIBLE (-2500 1225);
FORCEPROP 2 LAST ROOM VDDQ_KLM_PWR_VR
J 0
(-3050 1300);
DISPLAY 1.361702 (-3050 1300);
PAINT ORANGE (-3050 1300);
DISPLAY INVISIBLE (-3050 1300);
FORCEPROP 2 LAST PATH I4
J 0
(-2750 1275);
DISPLAY 1.021277 (-2750 1275);
PAINT ORANGE (-2750 1275);
DISPLAY INVISIBLE (-2750 1275);
FORCEPROP 1 LAST OFFPAGE TRUE
J 0
(-2175 1100);
DISPLAY 1.170213 (-2175 1100);
PAINT GREEN (-2175 1100);
DISPLAY INVISIBLE (-2175 1100);
FORCEPROP 1 LAST COMMENT_BODY TRUE
J 0
(-2375 1125);
DISPLAY 1.170213 (-2375 1125);
PAINT GREEN (-2375 1125);
DISPLAY INVISIBLE (-2375 1125);
FORCEADD CAP..1
(2650 275);
FORCEPROP 1 LAST PART_NUMBER A36096-046
J 0
(2700 125);
DISPLAY 0.617021 (2700 125);
PAINT BLUE (2700 125);
FORCEPROP 1 LAST MATERIAL X7R
J 0
(2700 175);
DISPLAY 0.617021 (2700 175);
PAINT SKYBLUE (2700 175);
FORCEPROP 1 LASTPIN (2650 175) $PN 2
J 0
(2660 155);
DISPLAY 0.617021 (2660 155);
PAINT ORANGE (2660 155);
FORCEPROP 1 LAST TOLERANCE 10%
J 0
(2700 225);
DISPLAY 0.617021 (2700 225);
PAINT SKYBLUE (2700 225);
FORCEPROP 1 LASTPIN (2650 375) $PN 1
J 0
(2660 355);
DISPLAY 0.617021 (2660 355);
PAINT ORANGE (2660 355);
FORCEPROP 1 LAST LOCATION C1B4
J 0
(2700 375);
DISPLAY 0.617021 (2700 375);
PAINT AQUA (2700 375);
FORCEPROP 1 LAST VOLTAGE 50V
J 0
(2700 275);
DISPLAY 0.617021 (2700 275);
PAINT SKYBLUE (2700 275);
FORCEPROP 1 LAST VALUE 1000PF
J 0
(2700 325);
DISPLAY 0.617021 (2700 325);
PAINT SKYBLUE (2700 325);
FORCEPROP 1 LAST PACK_TYPE 0402LF
J 0
(2700 75);
DISPLAY 0.617021 (2700 75);
PAINT SKYBLUE (2700 75);
FORCEPROP 2 LAST CDS_LIB mstr_discrete
J 0
(2650 275);
PAINT MONO (2650 275);
DISPLAY INVISIBLE (2650 275);
FORCEPROP 0 LAST ROOM VDDQ_KLM_PWR_VR
J 0
(2700 475);
DISPLAY 1.021277 (2700 475);
PAINT ORANGE (2700 475);
DISPLAY INVISIBLE (2700 475);
FORCEPROP 2 LAST CDS_LOCATION C1B4
J 0
(2700 375);
DISPLAY 0.617021 (2700 375);
PAINT AQUA (2700 375);
DISPLAY INVISIBLE (2700 375);
FORCEPROP 2 LAST SEC 1
J 0
(2700 475);
DISPLAY 0.680851 (2700 475);
PAINT MONO (2700 475);
DISPLAY INVISIBLE (2700 475);
FORCEPROP 2 LAST SEC_TYPE 0402LF
J 0
(2700 475);
DISPLAY 1.021277 (2700 475);
PAINT ORANGE (2700 475);
DISPLAY INVISIBLE (2700 475);
FORCEPROP 0 LAST CDS_SEC 1
J 0
(2700 425);
PAINT MONO (2700 425);
DISPLAY INVISIBLE (2700 425);
FORCEPROP 1 LAST PATH I40
J 0
(2700 425);
DISPLAY 0.978723 (2700 425);
PAINT WHITE (2700 425);
DISPLAY INVISIBLE (2700 425);
FORCEADD RES..1
(2525 975);
FORCEPROP 1 LAST WATTAGE 1/16W
J 2
(2500 825);
DISPLAY 0.617021 (2500 825);
PAINT SKYBLUE (2500 825);
FORCEPROP 1 LAST TOLERANCE 5%
J 0
(2475 875);
DISPLAY 0.617021 (2475 875);
PAINT SKYBLUE (2475 875);
FORCEPROP 1 LAST PACK_TYPE 0402
J 0
(2600 875);
DISPLAY 0.617021 (2600 875);
PAINT SKYBLUE (2600 875);
FORCEPROP 1 LASTPIN (2625 975) $PN 2
J 0
(2587 987);
DISPLAY 0.617021 (2587 987);
PAINT ORANGE (2587 987);
FORCEPROP 1 LAST VALUE 0.0
J 2
(2425 875);
DISPLAY 0.617021 (2425 875);
PAINT SKYBLUE (2425 875);
FORCEPROP 1 LAST PART_NUMBER G21497-005
J 0
(2375 925);
DISPLAY 0.617021 (2375 925);
PAINT BLUE (2375 925);
FORCEPROP 1 LAST LOCATION R1B10
J 0
(2475 1025);
DISPLAY 0.617021 (2475 1025);
PAINT AQUA (2475 1025);
FORCEPROP 1 LASTPIN (2425 975) $PN 1
J 0
(2437 987);
DISPLAY 0.617021 (2437 987);
PAINT ORANGE (2437 987);
FORCEPROP 1 LAST MATERIAL CHIP
J 0
(2525 825);
DISPLAY 0.617021 (2525 825);
PAINT SKYBLUE (2525 825);
FORCEPROP 2 LAST SEC 1
J 0
(2475 1175);
DISPLAY 0.680851 (2475 1175);
PAINT MONO (2475 1175);
DISPLAY INVISIBLE (2475 1175);
FORCEPROP 2 LAST SEC_TYPE 0402
J 0
(2475 1175);
DISPLAY 1.021277 (2475 1175);
PAINT ORANGE (2475 1175);
DISPLAY INVISIBLE (2475 1175);
FORCEPROP 2 LAST ROOM VDDQ_KLM_PWR_VR
J 0
(2475 1075);
DISPLAY 1.361702 (2475 1075);
PAINT ORANGE (2475 1075);
DISPLAY INVISIBLE (2475 1075);
FORCEPROP 2 LAST CDS_LIB mstr_discrete
J 0
(2525 975);
PAINT ORANGE (2525 975);
DISPLAY INVISIBLE (2525 975);
FORCEPROP 2 LAST CDS_LOCATION R1B10
J 0
(2475 1025);
DISPLAY 0.617021 (2475 1025);
PAINT AQUA (2475 1025);
DISPLAY INVISIBLE (2475 1025);
FORCEPROP 0 LAST CDS_SEC 1
J 0
(2475 1075);
PAINT MONO (2475 1075);
DISPLAY INVISIBLE (2475 1075);
FORCEPROP 1 LAST PATH I41
J 0
(2475 1125);
DISPLAY 0.978723 (2475 1125);
PAINT WHITE (2475 1125);
DISPLAY INVISIBLE (2475 1125);
FORCEADD CAP_A..1
(3100 -525);
FORCEPROP 1 LAST PART_NUMBER A36096-030
J 0
(3150 -675);
DISPLAY 0.617021 (3150 -675);
PAINT BLUE (3150 -675);
FORCEPROP 1 LAST LOCATION C1B2
J 0
(3150 -425);
DISPLAY 0.617021 (3150 -425);
PAINT AQUA (3150 -425);
FORCEPROP 1 LASTPIN (3100 -425) $PN 1
J 0
(3110 -445);
DISPLAY 0.617021 (3110 -445);
PAINT ORANGE (3110 -445);
FORCEPROP 1 LAST VALUE 0.1UF
J 0
(3150 -475);
DISPLAY 0.617021 (3150 -475);
PAINT SKYBLUE (3150 -475);
FORCEPROP 1 LAST MATERIAL X7R
J 0
(3150 -625);
DISPLAY 0.617021 (3150 -625);
PAINT SKYBLUE (3150 -625);
FORCEPROP 1 LASTPIN (3100 -625) $PN 2
J 0
(3110 -645);
DISPLAY 0.617021 (3110 -645);
PAINT ORANGE (3110 -645);
FORCEPROP 1 LAST PACK_TYPE 0402V
J 0
(3150 -725);
DISPLAY 0.617021 (3150 -725);
PAINT SKYBLUE (3150 -725);
FORCEPROP 1 LAST VOLTAGE 16V
J 0
(3150 -525);
DISPLAY 0.617021 (3150 -525);
PAINT SKYBLUE (3150 -525);
FORCEPROP 1 LAST TOLERANCE 10%
J 0
(3150 -575);
DISPLAY 0.617021 (3150 -575);
PAINT SKYBLUE (3150 -575);
FORCEPROP 2 LAST CDS_LIB dev_discrete
J 0
(3100 -525);
PAINT ORANGE (3100 -525);
DISPLAY INVISIBLE (3100 -525);
FORCEPROP 2 LAST ROOM VDDQ_KLM_PWR_VR
J 0
(3150 -375);
DISPLAY 1.361702 (3150 -375);
PAINT ORANGE (3150 -375);
DISPLAY INVISIBLE (3150 -375);
FORCEPROP 2 LAST CDS_LOCATION C1B2
J 0
(3150 -425);
DISPLAY 0.617021 (3150 -425);
PAINT AQUA (3150 -425);
DISPLAY INVISIBLE (3150 -425);
FORCEPROP 2 LAST CDS_SEC 1
J 0
(3150 -375);
PAINT ORANGE (3150 -375);
DISPLAY INVISIBLE (3150 -375);
FORCEPROP 2 LAST SEC_TYPE 0402V
J 0
(3150 -300);
DISPLAY 1.021277 (3150 -300);
PAINT ORANGE (3150 -300);
DISPLAY INVISIBLE (3150 -300);
FORCEPROP 2 LAST SEC 1
J 0
(3150 -300);
DISPLAY 0.680851 (3150 -300);
PAINT MONO (3150 -300);
DISPLAY INVISIBLE (3150 -300);
FORCEPROP 1 LAST PATH I44
J 0
(3150 -375);
DISPLAY 0.978723 (3150 -375);
PAINT WHITE (3150 -375);
DISPLAY INVISIBLE (3150 -375);
FORCEADD CAP_A..1
(3500 -525);
FORCEPROP 1 LAST PACK_TYPE 0402V
J 0
(3550 -725);
DISPLAY 0.617021 (3550 -725);
PAINT SKYBLUE (3550 -725);
FORCEPROP 1 LAST LOCATION C1B3
J 0
(3550 -425);
DISPLAY 0.617021 (3550 -425);
PAINT AQUA (3550 -425);
FORCEPROP 1 LAST VOLTAGE 6.3V
J 0
(3550 -525);
DISPLAY 0.617021 (3550 -525);
PAINT SKYBLUE (3550 -525);
FORCEPROP 1 LASTPIN (3500 -625) $PN 2
J 0
(3510 -645);
DISPLAY 0.617021 (3510 -645);
PAINT ORANGE (3510 -645);
FORCEPROP 1 LASTPIN (3500 -425) $PN 1
J 0
(3510 -445);
DISPLAY 0.617021 (3510 -445);
PAINT ORANGE (3510 -445);
FORCEPROP 1 LAST VALUE 1.0UF
J 0
(3550 -475);
DISPLAY 0.617021 (3550 -475);
PAINT SKYBLUE (3550 -475);
FORCEPROP 1 LAST MATERIAL X6S
J 0
(3550 -625);
DISPLAY 0.617021 (3550 -625);
PAINT SKYBLUE (3550 -625);
FORCEPROP 1 LAST PART_NUMBER D97712-004
J 0
(3550 -675);
DISPLAY 0.617021 (3550 -675);
PAINT BLUE (3550 -675);
FORCEPROP 1 LAST TOLERANCE 10%
J 0
(3550 -575);
DISPLAY 0.617021 (3550 -575);
PAINT SKYBLUE (3550 -575);
FORCEPROP 2 LAST ROOM VDDQ_KLM_PWR_VR
J 0
(3550 -375);
DISPLAY 1.361702 (3550 -375);
PAINT ORANGE (3550 -375);
DISPLAY INVISIBLE (3550 -375);
FORCEPROP 2 LAST SEC 1
J 0
(3550 -325);
DISPLAY 0.680851 (3550 -325);
PAINT MONO (3550 -325);
DISPLAY INVISIBLE (3550 -325);
FORCEPROP 2 LAST SEC_TYPE 0402V
J 0
(3550 -325);
DISPLAY 1.021277 (3550 -325);
PAINT ORANGE (3550 -325);
DISPLAY INVISIBLE (3550 -325);
FORCEPROP 2 LAST CDS_SEC 1
J 0
(3550 -375);
PAINT ORANGE (3550 -375);
DISPLAY INVISIBLE (3550 -375);
FORCEPROP 2 LAST CDS_LOCATION C1B3
J 0
(3550 -425);
DISPLAY 0.617021 (3550 -425);
PAINT AQUA (3550 -425);
DISPLAY INVISIBLE (3550 -425);
FORCEPROP 2 LAST CDS_LIB dev_discrete
J 0
(3500 -525);
PAINT ORANGE (3500 -525);
DISPLAY INVISIBLE (3500 -525);
FORCEPROP 1 LAST PATH I45
J 0
(3550 -375);
DISPLAY 0.978723 (3550 -375);
PAINT WHITE (3550 -375);
DISPLAY INVISIBLE (3550 -375);
FORCEADD RES..1
(2950 1125);
FORCEPROP 1 LAST WATTAGE 1/16W
J 0
(3100 1125);
DISPLAY 0.617021 (3100 1125);
PAINT SKYBLUE (3100 1125);
FORCEPROP 1 LAST PACK_TYPE 0402
J 0
(3700 1125);
DISPLAY 0.617021 (3700 1125);
PAINT SKYBLUE (3700 1125);
FORCEPROP 1 LASTPIN (2850 1125) $PN 1
J 0
(2862 1137);
DISPLAY 0.617021 (2862 1137);
PAINT ORANGE (2862 1137);
FORCEPROP 1 LASTPIN (3050 1125) $PN 2
J 0
(3012 1137);
DISPLAY 0.617021 (3012 1137);
PAINT ORANGE (3012 1137);
FORCEPROP 1 LAST VALUE 0.0
J 0
(2650 1125);
DISPLAY 0.617021 (2650 1125);
PAINT SKYBLUE (2650 1125);
FORCEPROP 1 LAST LOCATION R12W35
J 0
(2450 1125);
DISPLAY 0.617021 (2450 1125);
PAINT AQUA (2450 1125);
FORCEPROP 1 LAST PART_NUMBER G21497-005
J 0
(3450 1125);
DISPLAY 0.617021 (3450 1125);
PAINT BLUE (3450 1125);
FORCEPROP 1 LAST MATERIAL EMPTY
J 0
(3300 1125);
DISPLAY 0.617021 (3300 1125);
PAINT RED (3300 1125);
FORCEPROP 1 LAST TOLERANCE 5%
J 0
(2775 1125);
DISPLAY 0.617021 (2775 1125);
PAINT SKYBLUE (2775 1125);
FORCEPROP 2 LAST CDS_LIB mstr_discrete
J 0
(2950 1125);
PAINT ORANGE (2950 1125);
DISPLAY INVISIBLE (2950 1125);
FORCEPROP 0 LAST SEC 1
J 0
(2900 1275);
DISPLAY 0.680851 (2900 1275);
PAINT MONO (2900 1275);
DISPLAY INVISIBLE (2900 1275);
FORCEPROP 0 LAST ROOM NV_DIMM
J 0
(2900 1325);
DISPLAY 1.021277 (2900 1325);
PAINT ORANGE (2900 1325);
DISPLAY INVISIBLE (2900 1325);
FORCEPROP 2 LAST SEC_TYPE 0402
J 0
(2900 1325);
DISPLAY 1.021277 (2900 1325);
PAINT ORANGE (2900 1325);
DISPLAY INVISIBLE (2900 1325);
FORCEPROP 0 LAST BOM_COST MEM_NV
J 0
(2900 1425);
DISPLAY 1.021277 (2900 1425);
PAINT ORANGE (2900 1425);
DISPLAY INVISIBLE (2900 1425);
FORCEPROP 2 LAST CDS_LOCATION R12W35
J 0
(2900 1175);
DISPLAY 0.617021 (2900 1175);
PAINT AQUA (2900 1175);
DISPLAY INVISIBLE (2900 1175);
FORCEPROP 0 LAST CDS_SEC 1
J 0
(3700 1175);
PAINT MONO (3700 1175);
DISPLAY INVISIBLE (3700 1175);
FORCEPROP 1 LAST PATH I46
J 0
(2900 1275);
DISPLAY 0.978723 (2900 1275);
PAINT WHITE (2900 1275);
DISPLAY INVISIBLE (2900 1275);
FORCEADD RES..1
(2325 1675);
FORCEPROP 1 LAST MATERIAL CHIP
J 0
(2550 1625);
DISPLAY 0.617021 (2550 1625);
PAINT SKYBLUE (2550 1625);
FORCEPROP 1 LAST PACK_TYPE 0402
J 0
(2425 1625);
DISPLAY 0.617021 (2425 1625);
PAINT SKYBLUE (2425 1625);
FORCEPROP 1 LAST PART_NUMBER G21497-005
J 0
(2200 1575);
DISPLAY 0.617021 (2200 1575);
PAINT BLUE (2200 1575);
FORCEPROP 1 LASTPIN (2225 1675) $PN 1
J 0
(2237 1687);
DISPLAY 0.617021 (2237 1687);
PAINT ORANGE (2237 1687);
FORCEPROP 1 LAST TOLERANCE 5%
J 0
(2325 1625);
DISPLAY 0.617021 (2325 1625);
PAINT SKYBLUE (2325 1625);
FORCEPROP 1 LASTPIN (2425 1675) $PN 2
J 0
(2387 1687);
DISPLAY 0.617021 (2387 1687);
PAINT ORANGE (2387 1687);
FORCEPROP 1 LAST VALUE 0.0
J 2
(2300 1625);
DISPLAY 0.617021 (2300 1625);
PAINT SKYBLUE (2300 1625);
FORCEPROP 1 LAST WATTAGE 1/16W
J 2
(2175 1575);
DISPLAY 0.617021 (2175 1575);
PAINT SKYBLUE (2175 1575);
FORCEPROP 1 LAST LOCATION R1B11
J 0
(2075 1625);
DISPLAY 0.617021 (2075 1625);
PAINT AQUA (2075 1625);
FORCEPROP 2 LAST CDS_LOCATION R1B11
J 0
(2375 1725);
DISPLAY 0.617021 (2375 1725);
PAINT AQUA (2375 1725);
DISPLAY INVISIBLE (2375 1725);
FORCEPROP 2 LAST CDS_LIB mstr_discrete
J 0
(2325 1675);
PAINT ORANGE (2325 1675);
DISPLAY INVISIBLE (2325 1675);
FORCEPROP 2 LAST SEC 1
J 0
(2275 1900);
DISPLAY 0.680851 (2275 1900);
PAINT MONO (2275 1900);
DISPLAY INVISIBLE (2275 1900);
FORCEPROP 2 LAST SEC_TYPE 0402
J 0
(2275 1900);
DISPLAY 1.021277 (2275 1900);
PAINT ORANGE (2275 1900);
DISPLAY INVISIBLE (2275 1900);
FORCEPROP 2 LAST ROOM VDDQ_KLM_PWR_VR
J 0
(2275 1775);
DISPLAY 1.361702 (2275 1775);
PAINT ORANGE (2275 1775);
DISPLAY INVISIBLE (2275 1775);
FORCEPROP 0 LAST CDS_SEC 1
J 0
(2550 1675);
PAINT MONO (2550 1675);
DISPLAY INVISIBLE (2550 1675);
FORCEPROP 1 LAST PATH I48
J 0
(2275 1825);
DISPLAY 0.978723 (2275 1825);
PAINT WHITE (2275 1825);
DISPLAY INVISIBLE (2275 1825);
FORCEADD RES..2
(1825 2350);
FORCEPROP 1 LAST TOLERANCE 1%
J 0
(1870 2375);
DISPLAY 0.617021 (1870 2375);
PAINT SKYBLUE (1870 2375);
FORCEPROP 1 LASTPIN (1825 2450) $PN 1
J 0
(1830 2412);
DISPLAY 0.617021 (1830 2412);
PAINT ORANGE (1830 2412);
FORCEPROP 1 LASTPIN (1825 2250) $PN 2
J 0
(1830 2260);
DISPLAY 0.617021 (1830 2260);
PAINT ORANGE (1830 2260);
FORCEPROP 1 LAST PACK_TYPE 0402
J 0
(1865 2175);
DISPLAY 0.617021 (1865 2175);
PAINT SKYBLUE (1865 2175);
FORCEPROP 1 LAST PART_NUMBER G21796-026
J 0
(1865 2225);
DISPLAY 0.617021 (1865 2225);
PAINT BLUE (1865 2225);
FORCEPROP 1 LAST MATERIAL CHIP
J 0
(1865 2275);
DISPLAY 0.617021 (1865 2275);
PAINT SKYBLUE (1865 2275);
FORCEPROP 1 LAST WATTAGE 1/16W
J 0
(1865 2325);
DISPLAY 0.617021 (1865 2325);
PAINT SKYBLUE (1865 2325);
FORCEPROP 1 LAST VALUE 1.00K
J 0
(1870 2425);
DISPLAY 0.617021 (1870 2425);
PAINT SKYBLUE (1870 2425);
FORCEPROP 1 LAST LOCATION R1B1
J 0
(1870 2475);
DISPLAY 0.617021 (1870 2475);
PAINT AQUA (1870 2475);
FORCEPROP 2 LAST CDS_LOCATION R1B1
J 0
(1870 2475);
DISPLAY 0.617021 (1870 2475);
PAINT AQUA (1870 2475);
DISPLAY INVISIBLE (1870 2475);
FORCEPROP 2 LAST CDS_LIB mstr_discrete
J 0
(1825 2350);
PAINT ORANGE (1825 2350);
DISPLAY INVISIBLE (1825 2350);
FORCEPROP 2 LAST SEC_TYPE 0402
J 0
(1875 2575);
DISPLAY 1.021277 (1875 2575);
PAINT ORANGE (1875 2575);
DISPLAY INVISIBLE (1875 2575);
FORCEPROP 2 LAST SEC 1
J 0
(1875 2575);
DISPLAY 0.680851 (1875 2575);
PAINT MONO (1875 2575);
DISPLAY INVISIBLE (1875 2575);
FORCEPROP 0 LAST ROOM RQ_PVDDQ_KLM_VRHOT_LVT3_N
J 0
(1875 2575);
DISPLAY 1.021277 (1875 2575);
PAINT ORANGE (1875 2575);
DISPLAY INVISIBLE (1875 2575);
FORCEPROP 0 LAST CDS_SEC 1
J 0
(1875 2525);
PAINT MONO (1875 2525);
DISPLAY INVISIBLE (1875 2525);
FORCEPROP 1 LAST PATH I49
J 0
(1875 2525);
DISPLAY 0.978723 (1875 2525);
PAINT WHITE (1875 2525);
DISPLAY INVISIBLE (1875 2525);
FORCEADD OFFPAGE..1
(-2500 1075);
FORCEPROP 2 LAST $XR0 227 
J 0
(-2752 1075);
DISPLAY 0.638298 (-2752 1075);
PAINT MONO (-2752 1075);
FORCEPROP 2 LAST ROOM VDDQ_KLM_PWR_VR
J 0
(-3050 1150);
DISPLAY 1.361702 (-3050 1150);
PAINT ORANGE (-3050 1150);
DISPLAY INVISIBLE (-3050 1150);
FORCEPROP 2 LAST CDS_LIB mstr_standard
J 0
(-2500 1075);
PAINT ORANGE (-2500 1075);
DISPLAY INVISIBLE (-2500 1075);
FORCEPROP 2 LAST PATH I5
J 0
(-2750 1125);
DISPLAY 1.021277 (-2750 1125);
PAINT ORANGE (-2750 1125);
DISPLAY INVISIBLE (-2750 1125);
FORCEPROP 1 LAST OFFPAGE TRUE
J 0
(-2175 950);
DISPLAY 1.170213 (-2175 950);
PAINT GREEN (-2175 950);
DISPLAY INVISIBLE (-2175 950);
FORCEPROP 1 LAST COMMENT_BODY TRUE
J 0
(-2375 975);
DISPLAY 1.170213 (-2375 975);
PAINT GREEN (-2375 975);
DISPLAY INVISIBLE (-2375 975);
FORCEADD RES..2
(2100 2350);
FORCEPROP 1 LAST VALUE 1.00K
J 0
(2145 2425);
DISPLAY 0.617021 (2145 2425);
PAINT SKYBLUE (2145 2425);
FORCEPROP 1 LAST WATTAGE 1/16W
J 0
(2140 2325);
DISPLAY 0.617021 (2140 2325);
PAINT SKYBLUE (2140 2325);
FORCEPROP 1 LASTPIN (2100 2450) $PN 1
J 0
(2105 2412);
DISPLAY 0.617021 (2105 2412);
PAINT ORANGE (2105 2412);
FORCEPROP 1 LAST TOLERANCE 1%
J 0
(2145 2375);
DISPLAY 0.617021 (2145 2375);
PAINT SKYBLUE (2145 2375);
FORCEPROP 1 LAST MATERIAL CHIP
J 0
(2140 2275);
DISPLAY 0.617021 (2140 2275);
PAINT SKYBLUE (2140 2275);
FORCEPROP 1 LASTPIN (2100 2250) $PN 2
J 0
(2105 2260);
DISPLAY 0.617021 (2105 2260);
PAINT ORANGE (2105 2260);
FORCEPROP 1 LAST LOCATION R1B2
J 0
(2145 2475);
DISPLAY 0.617021 (2145 2475);
PAINT AQUA (2145 2475);
FORCEPROP 1 LAST PACK_TYPE 0402
J 0
(2140 2175);
DISPLAY 0.617021 (2140 2175);
PAINT SKYBLUE (2140 2175);
FORCEPROP 1 LAST PART_NUMBER G21796-026
J 0
(2140 2225);
DISPLAY 0.617021 (2140 2225);
PAINT BLUE (2140 2225);
FORCEPROP 2 LAST SEC_TYPE 0402
J 0
(2150 2600);
DISPLAY 1.021277 (2150 2600);
PAINT ORANGE (2150 2600);
DISPLAY INVISIBLE (2150 2600);
FORCEPROP 2 LAST CDS_LOCATION R1B2
J 0
(2145 2475);
DISPLAY 0.617021 (2145 2475);
PAINT AQUA (2145 2475);
DISPLAY INVISIBLE (2145 2475);
FORCEPROP 2 LAST SEC 1
J 0
(2150 2600);
DISPLAY 0.680851 (2150 2600);
PAINT MONO (2150 2600);
DISPLAY INVISIBLE (2150 2600);
FORCEPROP 2 LAST ROOM VDDQ_KLM_PWR_VR
J 0
(2150 2525);
DISPLAY 1.361702 (2150 2525);
PAINT ORANGE (2150 2525);
DISPLAY INVISIBLE (2150 2525);
FORCEPROP 2 LAST CDS_LIB mstr_discrete
J 2
(2100 2350);
PAINT ORANGE (2100 2350);
DISPLAY INVISIBLE (2100 2350);
FORCEPROP 0 LAST CDS_SEC 1
J 0
(2150 2525);
PAINT MONO (2150 2525);
DISPLAY INVISIBLE (2150 2525);
FORCEPROP 1 LAST PATH I50
J 0
(2150 2525);
DISPLAY 0.978723 (2150 2525);
PAINT WHITE (2150 2525);
DISPLAY INVISIBLE (2150 2525);
FORCEADD OFFPAGE..2
(2700 2100);
FORCEPROP 2 LAST $XR0 230 
J 0
(2889 2100);
DISPLAY 0.638298 (2889 2100);
PAINT MONO (2889 2100);
FORCEPROP 2 LAST CDS_LIB mstr_standard
J 0
(2700 2100);
PAINT MONO (2700 2100);
DISPLAY INVISIBLE (2700 2100);
FORCEPROP 2 LAST ROOM VDDQ_KLM_PWR_VR
J 0
(2275 2175);
DISPLAY 1.361702 (2275 2175);
PAINT ORANGE (2275 2175);
DISPLAY INVISIBLE (2275 2175);
FORCEPROP 2 LAST PATH I51
J 0
(2900 2150);
DISPLAY 1.021277 (2900 2150);
PAINT ORANGE (2900 2150);
DISPLAY INVISIBLE (2900 2150);
FORCEPROP 1 LAST OFFPAGE TRUE
J 0
(3025 1975);
DISPLAY 1.170213 (3025 1975);
PAINT GREEN (3025 1975);
DISPLAY INVISIBLE (3025 1975);
FORCEPROP 1 LAST COMMENT_BODY TRUE
J 0
(2655 2005);
DISPLAY 1.170213 (2655 2005);
PAINT GREEN (2655 2005);
DISPLAY INVISIBLE (2655 2005);
FORCEADD P3V3_STBY..1
(2200 3000);
FORCEPROP 3 LASTPIN (2200 2950) SIG_NAME P3V3_STBY\g
J 0
(2210 2960);
DISPLAY 0.659574 (2210 2960);
PAINT MONO (2210 2960);
DISPLAY INVISIBLE (2210 2960);
FORCEPROP 2 LAST CDS_LIB mstr_symbols
J 0
(2200 3000);
PAINT ORANGE (2200 3000);
DISPLAY INVISIBLE (2200 3000);
FORCEPROP 1 LAST SIZE 1B
J 0
(2245 3022);
DISPLAY 0.340426 (2245 3022);
PAINT GREEN (2245 3022);
DISPLAY INVISIBLE (2245 3022);
FORCEPROP 1 LAST VOLTAGE 3.3V
J 0
(2155 2957);
DISPLAY 0.340426 (2155 2957);
PAINT SKYBLUE (2155 2957);
DISPLAY INVISIBLE (2155 2957);
FORCEPROP 1 LAST PATH I52
J 0
(2245 3002);
DISPLAY 0.340426 (2245 3002);
PAINT GREEN (2245 3002);
DISPLAY INVISIBLE (2245 3002);
FORCEPROP 1 LAST BODY_TYPE PLUMBING
J 0
(2155 2957);
DISPLAY 0.340426 (2155 2957);
PAINT GREEN (2155 2957);
DISPLAY INVISIBLE (2155 2957);
FORCEPROP 1 LAST HDL_POWER P3V3_STBY
J 0
(1900 2875);
DISPLAY 0.872340 (1900 2875);
PAINT ORANGE (1900 2875);
DISPLAY INVISIBLE (1900 2875);
FORCEADD RES..1
(2950 1525);
FORCEPROP 1 LAST PART_NUMBER G21497-005
J 0
(2700 1575);
DISPLAY 0.617021 (2700 1575);
PAINT BLUE (2700 1575);
FORCEPROP 1 LAST TOLERANCE 5%
J 0
(3000 1625);
DISPLAY 0.617021 (3000 1625);
PAINT SKYBLUE (3000 1625);
FORCEPROP 1 LASTPIN (2850 1525) $PN 1
J 0
(2862 1537);
DISPLAY 0.617021 (2862 1537);
PAINT ORANGE (2862 1537);
FORCEPROP 1 LAST LOCATION R12W36
J 0
(2700 1625);
DISPLAY 0.617021 (2700 1625);
PAINT AQUA (2700 1625);
FORCEPROP 1 LAST VALUE 0.0
J 0
(2900 1625);
DISPLAY 0.617021 (2900 1625);
PAINT SKYBLUE (2900 1625);
FORCEPROP 1 LASTPIN (3050 1525) $PN 2
J 0
(3012 1537);
DISPLAY 0.617021 (3012 1537);
PAINT ORANGE (3012 1537);
FORCEPROP 1 LAST PACK_TYPE 0402
J 0
(2950 1575);
DISPLAY 0.617021 (2950 1575);
PAINT SKYBLUE (2950 1575);
FORCEPROP 1 LAST MATERIAL EMPTY
J 0
(3250 1625);
DISPLAY 0.617021 (3250 1625);
PAINT RED (3250 1625);
FORCEPROP 1 LAST WATTAGE 1/16W
J 0
(3100 1625);
DISPLAY 0.617021 (3100 1625);
PAINT SKYBLUE (3100 1625);
FORCEPROP 2 LAST CDS_LIB mstr_discrete
J 0
(2950 1525);
PAINT ORANGE (2950 1525);
DISPLAY INVISIBLE (2950 1525);
FORCEPROP 0 LAST SEC 1
J 0
(2900 1675);
DISPLAY 0.680851 (2900 1675);
PAINT MONO (2900 1675);
DISPLAY INVISIBLE (2900 1675);
FORCEPROP 0 LAST ROOM NV_DIMM
J 0
(2900 1725);
DISPLAY 1.021277 (2900 1725);
PAINT ORANGE (2900 1725);
DISPLAY INVISIBLE (2900 1725);
FORCEPROP 2 LAST SEC_TYPE 0402
J 0
(2900 1725);
DISPLAY 1.021277 (2900 1725);
PAINT ORANGE (2900 1725);
DISPLAY INVISIBLE (2900 1725);
FORCEPROP 0 LAST BOM_COST MEM_NV
J 0
(2900 1825);
DISPLAY 1.021277 (2900 1825);
PAINT ORANGE (2900 1825);
DISPLAY INVISIBLE (2900 1825);
FORCEPROP 2 LAST CDS_LOCATION R12W36
J 0
(2900 1575);
DISPLAY 0.617021 (2900 1575);
PAINT AQUA (2900 1575);
DISPLAY INVISIBLE (2900 1575);
FORCEPROP 0 LAST CDS_SEC 1
J 0
(3250 1675);
PAINT MONO (3250 1675);
DISPLAY INVISIBLE (3250 1675);
FORCEPROP 1 LAST PATH I53
J 0
(2900 1675);
DISPLAY 0.978723 (2900 1675);
PAINT WHITE (2900 1675);
DISPLAY INVISIBLE (2900 1675);
FORCEADD RES..1
(3025 1725);
FORCEPROP 1 LAST TOLERANCE 1%
J 0
(3000 1775);
DISPLAY 0.617021 (3000 1775);
PAINT SKYBLUE (3000 1775);
FORCEPROP 1 LAST PACK_TYPE 0402
J 0
(2825 1725);
DISPLAY 0.617021 (2825 1725);
PAINT SKYBLUE (2825 1725);
FORCEPROP 1 LAST MATERIAL CHIP
J 0
(2700 1725);
DISPLAY 0.617021 (2700 1725);
PAINT SKYBLUE (2700 1725);
FORCEPROP 1 LAST LOCATION R1B4
J 0
(2725 1775);
DISPLAY 0.617021 (2725 1775);
PAINT AQUA (2725 1775);
FORCEPROP 1 LASTPIN (2925 1725) $PN 1
J 0
(2937 1737);
DISPLAY 0.617021 (2937 1737);
PAINT ORANGE (2937 1737);
FORCEPROP 1 LAST VALUE 33.2
J 2
(2950 1775);
DISPLAY 0.617021 (2950 1775);
PAINT SKYBLUE (2950 1775);
FORCEPROP 1 LASTPIN (3125 1725) $PN 2
J 0
(3087 1737);
DISPLAY 0.617021 (3087 1737);
PAINT ORANGE (3087 1737);
FORCEPROP 1 LAST WATTAGE 1/16W
J 2
(3250 1775);
DISPLAY 0.617021 (3250 1775);
PAINT SKYBLUE (3250 1775);
FORCEPROP 1 LAST PART_NUMBER G21796-074
J 0
(3325 1775);
DISPLAY 0.617021 (3325 1775);
PAINT BLUE (3325 1775);
FORCEPROP 2 LAST SEC_TYPE 0402
J 0
(2975 1925);
DISPLAY 1.021277 (2975 1925);
PAINT ORANGE (2975 1925);
DISPLAY INVISIBLE (2975 1925);
FORCEPROP 2 LAST SEC 1
J 0
(2975 1925);
DISPLAY 0.680851 (2975 1925);
PAINT MONO (2975 1925);
DISPLAY INVISIBLE (2975 1925);
FORCEPROP 2 LAST CDS_LIB mstr_discrete
J 0
(3025 1725);
PAINT MONO (3025 1725);
DISPLAY INVISIBLE (3025 1725);
FORCEPROP 2 LAST CDS_LOCATION R1B4
J 0
(2975 1775);
DISPLAY 0.617021 (2975 1775);
PAINT AQUA (2975 1775);
DISPLAY INVISIBLE (2975 1775);
FORCEPROP 0 LAST CDS_SEC 1
J 0
(3325 1825);
PAINT MONO (3325 1825);
DISPLAY INVISIBLE (3325 1825);
FORCEPROP 1 LAST PATH I54
J 0
(2975 1875);
DISPLAY 0.978723 (2975 1875);
PAINT WHITE (2975 1875);
DISPLAY INVISIBLE (2975 1875);
FORCEADD RES..1
(3025 1825);
FORCEPROP 1 LAST PACK_TYPE 0402
J 0
(3125 1975);
DISPLAY 0.617021 (3125 1975);
PAINT SKYBLUE (3125 1975);
FORCEPROP 1 LAST PART_NUMBER G21796-250
J 0
(2975 1925);
DISPLAY 0.617021 (2975 1925);
PAINT BLUE (2975 1925);
FORCEPROP 1 LAST MATERIAL CHIP
J 0
(2825 1925);
DISPLAY 0.617021 (2825 1925);
PAINT SKYBLUE (2825 1925);
FORCEPROP 1 LAST WATTAGE 1/16W
J 2
(2950 1975);
DISPLAY 0.617021 (2950 1975);
PAINT SKYBLUE (2950 1975);
FORCEPROP 1 LASTPIN (2925 1825) $PN 1
J 0
(2912 1837);
DISPLAY 0.617021 (2912 1837);
PAINT ORANGE (2912 1837);
FORCEPROP 1 LASTPIN (3125 1825) $PN 2
J 0
(3112 1837);
DISPLAY 0.617021 (3112 1837);
PAINT ORANGE (3112 1837);
FORCEPROP 1 LAST VALUE 22.1
J 2
(2925 1875);
DISPLAY 0.617021 (2925 1875);
PAINT SKYBLUE (2925 1875);
FORCEPROP 1 LAST LOCATION R1B5
J 0
(2975 1975);
DISPLAY 0.617021 (2975 1975);
PAINT AQUA (2975 1975);
FORCEPROP 1 LAST TOLERANCE 1.0%
J 0
(3150 1875);
DISPLAY 0.617021 (3150 1875);
PAINT SKYBLUE (3150 1875);
FORCEPROP 0 LAST POP NOPOP
J 0
(2950 1875);
DISPLAY 0.638298 (2950 1875);
PAINT RED (2950 1875);
FORCEPROP 2 LAST CDS_LIB mstr_discrete
J 0
(3025 1825);
PAINT MONO (3025 1825);
DISPLAY INVISIBLE (3025 1825);
FORCEPROP 2 LAST ROOM VDDQ_KLM_PWR_VR
J 0
(2975 1925);
DISPLAY 1.361702 (2975 1925);
PAINT ORANGE (2975 1925);
DISPLAY INVISIBLE (2975 1925);
FORCEPROP 2 LAST CDS_LOCATION R1B5
J 0
(2975 1875);
DISPLAY 0.617021 (2975 1875);
PAINT AQUA (2975 1875);
DISPLAY INVISIBLE (2975 1875);
FORCEPROP 2 LAST SEC 1
J 0
(2975 2025);
DISPLAY 0.680851 (2975 2025);
PAINT MONO (2975 2025);
DISPLAY INVISIBLE (2975 2025);
FORCEPROP 2 LAST SEC_TYPE 0402
J 0
(2975 2025);
DISPLAY 1.021277 (2975 2025);
PAINT ORANGE (2975 2025);
DISPLAY INVISIBLE (2975 2025);
FORCEPROP 0 LAST CDS_SEC 1
J 0
(3125 2025);
PAINT MONO (3125 2025);
DISPLAY INVISIBLE (3125 2025);
FORCEPROP 1 LAST PATH I55
J 0
(2975 1975);
DISPLAY 0.978723 (2975 1975);
PAINT WHITE (2975 1975);
DISPLAY INVISIBLE (2975 1975);
FORCEADD RES..2
(3750 2075);
FORCEPROP 1 LAST LOCATION R9M7
J 0
(3795 2200);
DISPLAY 0.617021 (3795 2200);
PAINT AQUA (3795 2200);
FORCEPROP 1 LAST VALUE 100.0
J 0
(3795 2150);
DISPLAY 0.617021 (3795 2150);
PAINT SKYBLUE (3795 2150);
FORCEPROP 1 LASTPIN (3750 2175) $PN 1
J 0
(3755 2137);
DISPLAY 0.617021 (3755 2137);
PAINT ORANGE (3755 2137);
FORCEPROP 1 LAST PACK_TYPE 0402
J 0
(3790 1900);
DISPLAY 0.617021 (3790 1900);
PAINT SKYBLUE (3790 1900);
FORCEPROP 1 LAST PART_NUMBER G21796-017
J 0
(3790 1950);
DISPLAY 0.617021 (3790 1950);
PAINT BLUE (3790 1950);
FORCEPROP 1 LASTPIN (3750 1975) $PN 2
J 0
(3755 1985);
DISPLAY 0.617021 (3755 1985);
PAINT ORANGE (3755 1985);
FORCEPROP 1 LAST MATERIAL EMPTY
J 0
(3790 2000);
DISPLAY 0.617021 (3790 2000);
PAINT RED (3790 2000);
FORCEPROP 1 LAST WATTAGE 1/16W
J 0
(3790 2050);
DISPLAY 0.617021 (3790 2050);
PAINT SKYBLUE (3790 2050);
FORCEPROP 1 LAST TOLERANCE 1%
J 0
(3795 2100);
DISPLAY 0.617021 (3795 2100);
PAINT SKYBLUE (3795 2100);
FORCEPROP 1 LAST PATH I57
J 0
(3800 2250);
DISPLAY 0.978723 (3800 2250);
PAINT WHITE (3800 2250);
DISPLAY INVISIBLE (3800 2250);
FORCEPROP 0 LAST CDS_SEC 1
J 0
(3800 2250);
PAINT MONO (3800 2250);
DISPLAY INVISIBLE (3800 2250);
FORCEPROP 2 LAST SEC_TYPE 0402
J 0
(3800 2325);
DISPLAY 1.021277 (3800 2325);
PAINT ORANGE (3800 2325);
DISPLAY INVISIBLE (3800 2325);
FORCEPROP 2 LAST SEC 1
J 0
(3800 2325);
DISPLAY 0.680851 (3800 2325);
PAINT MONO (3800 2325);
DISPLAY INVISIBLE (3800 2325);
FORCEPROP 2 LAST CDS_LOCATION R9M7
J 0
(3795 2200);
DISPLAY 0.617021 (3795 2200);
PAINT AQUA (3795 2200);
DISPLAY INVISIBLE (3795 2200);
FORCEPROP 2 LAST ROOM VDDQ_KLM_PWR_VR
J 0
(3800 2250);
DISPLAY 1.361702 (3800 2250);
PAINT ORANGE (3800 2250);
DISPLAY INVISIBLE (3800 2250);
FORCEPROP 2 LAST CDS_LIB mstr_discrete
J 0
(3750 2075);
PAINT ORANGE (3750 2075);
DISPLAY INVISIBLE (3750 2075);
FORCEADD PVCCIO_CPU1..1
(3750 2300);
FORCEPROP 3 LASTPIN (3750 2250) SIG_NAME PVCCIO_CPU1\g
J 0
(3760 2260);
DISPLAY 0.659574 (3760 2260);
PAINT MONO (3760 2260);
DISPLAY INVISIBLE (3760 2260);
FORCEPROP 1 LAST PATH I58
J 0
(3800 2325);
DISPLAY 0.872340 (3800 2325);
PAINT AQUA (3800 2325);
DISPLAY INVISIBLE (3800 2325);
FORCEPROP 1 LAST VOLTAGE 1.1V
J 0
(3705 2257);
DISPLAY 0.340426 (3705 2257);
PAINT SKYBLUE (3705 2257);
DISPLAY INVISIBLE (3705 2257);
FORCEPROP 2 LAST CDS_LIB mstr_symbols
J 0
(3750 2300);
PAINT ORANGE (3750 2300);
DISPLAY INVISIBLE (3750 2300);
FORCEPROP 1 LAST BODY_TYPE PLUMBING
J 0
(3705 2257);
DISPLAY 0.340426 (3705 2257);
PAINT GREEN (3705 2257);
DISPLAY INVISIBLE (3705 2257);
FORCEPROP 1 LAST HDL_POWER PVCCIO_CPU1
J 1
(3750 2350);
DISPLAY 0.872340 (3750 2350);
PAINT GREEN (3750 2350);
DISPLAY INVISIBLE (3750 2350);
FORCEADD OFFPAGE..1
R 2
(4100 -350);
FORCEPROP 2 LAST $XR0 226 
J 0
(4286 -350);
DISPLAY 0.638298 (4286 -350);
PAINT MONO (4286 -350);
FORCEPROP 2 LAST ROOM VDDQ_KLM_PWR_VR
J 0
(3675 -275);
DISPLAY 1.361702 (3675 -275);
PAINT ORANGE (3675 -275);
DISPLAY INVISIBLE (3675 -275);
FORCEPROP 2 LAST CDS_LIB mstr_standard
J 2
(4100 -350);
PAINT ORANGE (4100 -350);
DISPLAY INVISIBLE (4100 -350);
FORCEPROP 2 LAST PATH I59
J 0
(4300 -300);
DISPLAY 1.021277 (4300 -300);
PAINT ORANGE (4300 -300);
DISPLAY INVISIBLE (4300 -300);
FORCEPROP 1 LAST OFFPAGE TRUE
J 2
(3775 -475);
DISPLAY 1.170213 (3775 -475);
PAINT GREEN (3775 -475);
DISPLAY INVISIBLE (3775 -475);
FORCEPROP 1 LAST COMMENT_BODY TRUE
J 2
(3975 -450);
DISPLAY 1.170213 (3975 -450);
PAINT GREEN (3975 -450);
DISPLAY INVISIBLE (3975 -450);
FORCEADD OFFPAGE..1
(-2500 1175);
FORCEPROP 2 LAST $XR0 197 
J 0
(-2752 1175);
DISPLAY 0.638298 (-2752 1175);
PAINT MONO (-2752 1175);
FORCEPROP 2 LAST ROOM VDDQ_KLM_PWR_VR
J 0
(-3050 1250);
DISPLAY 1.361702 (-3050 1250);
PAINT ORANGE (-3050 1250);
DISPLAY INVISIBLE (-3050 1250);
FORCEPROP 2 LAST CDS_LIB mstr_standard
J 0
(-2500 1175);
PAINT ORANGE (-2500 1175);
DISPLAY INVISIBLE (-2500 1175);
FORCEPROP 2 LAST PATH I6
J 0
(-2750 1225);
DISPLAY 1.021277 (-2750 1225);
PAINT ORANGE (-2750 1225);
DISPLAY INVISIBLE (-2750 1225);
FORCEPROP 1 LAST OFFPAGE TRUE
J 0
(-2175 1050);
DISPLAY 1.170213 (-2175 1050);
PAINT GREEN (-2175 1050);
DISPLAY INVISIBLE (-2175 1050);
FORCEPROP 1 LAST COMMENT_BODY TRUE
J 0
(-2375 1075);
DISPLAY 1.170213 (-2375 1075);
PAINT GREEN (-2375 1075);
DISPLAY INVISIBLE (-2375 1075);
FORCEADD OFFPAGE..2
(4100 725);
FORCEPROP 2 LAST $XR0 227 
J 0
(4289 725);
DISPLAY 0.638298 (4289 725);
PAINT MONO (4289 725);
FORCEPROP 2 LAST ROOM VDDQ_KLM_PWR_VR
J 0
(3675 800);
DISPLAY 1.361702 (3675 800);
PAINT ORANGE (3675 800);
DISPLAY INVISIBLE (3675 800);
FORCEPROP 2 LAST CDS_LIB mstr_standard
J 0
(4100 725);
PAINT ORANGE (4100 725);
DISPLAY INVISIBLE (4100 725);
FORCEPROP 2 LAST PATH I60
J 0
(4300 775);
DISPLAY 1.021277 (4300 775);
PAINT ORANGE (4300 775);
DISPLAY INVISIBLE (4300 775);
FORCEPROP 1 LAST OFFPAGE TRUE
J 0
(4425 600);
DISPLAY 1.170213 (4425 600);
PAINT GREEN (4425 600);
DISPLAY INVISIBLE (4425 600);
FORCEPROP 1 LAST COMMENT_BODY TRUE
J 0
(4055 630);
DISPLAY 1.170213 (4055 630);
PAINT GREEN (4055 630);
DISPLAY INVISIBLE (4055 630);
FORCEADD OFFPAGE..2
(4100 775);
FORCEPROP 2 LAST $XR0 227 
J 0
(4289 775);
DISPLAY 0.638298 (4289 775);
PAINT MONO (4289 775);
FORCEPROP 2 LAST ROOM VDDQ_KLM_PWR_VR
J 0
(3675 850);
DISPLAY 1.361702 (3675 850);
PAINT ORANGE (3675 850);
DISPLAY INVISIBLE (3675 850);
FORCEPROP 2 LAST CDS_LIB mstr_standard
J 0
(4100 775);
PAINT ORANGE (4100 775);
DISPLAY INVISIBLE (4100 775);
FORCEPROP 2 LAST PATH I61
J 0
(4300 825);
DISPLAY 1.021277 (4300 825);
PAINT ORANGE (4300 825);
DISPLAY INVISIBLE (4300 825);
FORCEPROP 1 LAST OFFPAGE TRUE
J 0
(4425 650);
DISPLAY 1.170213 (4425 650);
PAINT GREEN (4425 650);
DISPLAY INVISIBLE (4425 650);
FORCEPROP 1 LAST COMMENT_BODY TRUE
J 0
(4055 680);
DISPLAY 1.170213 (4055 680);
PAINT GREEN (4055 680);
DISPLAY INVISIBLE (4055 680);
FORCEADD OFFPAGE..2
(4100 1025);
FORCEPROP 2 LAST $XR0 226 
J 0
(4289 1025);
DISPLAY 0.638298 (4289 1025);
PAINT MONO (4289 1025);
FORCEPROP 2 LAST CDS_LIB mstr_standard
J 0
(4100 1025);
PAINT ORANGE (4100 1025);
DISPLAY INVISIBLE (4100 1025);
FORCEPROP 2 LAST ROOM VDDQ_KLM_PWR_VR
J 0
(3675 1100);
DISPLAY 1.361702 (3675 1100);
PAINT ORANGE (3675 1100);
DISPLAY INVISIBLE (3675 1100);
FORCEPROP 2 LAST PATH I62
J 0
(4300 1075);
DISPLAY 1.021277 (4300 1075);
PAINT ORANGE (4300 1075);
DISPLAY INVISIBLE (4300 1075);
FORCEPROP 1 LAST OFFPAGE TRUE
J 0
(4425 900);
DISPLAY 1.170213 (4425 900);
PAINT GREEN (4425 900);
DISPLAY INVISIBLE (4425 900);
FORCEPROP 1 LAST COMMENT_BODY TRUE
J 0
(4055 930);
DISPLAY 1.170213 (4055 930);
PAINT GREEN (4055 930);
DISPLAY INVISIBLE (4055 930);
FORCEADD OFFPAGE..3
(4100 975);
FORCEPROP 2 LAST $XR2 223 
J 0
(4524 975);
DISPLAY 0.638298 (4524 975);
PAINT MONO (4524 975);
FORCEPROP 2 LAST $XR1 193 
J 0
(4404 975);
DISPLAY 0.638298 (4404 975);
PAINT MONO (4404 975);
FORCEPROP 2 LAST $XR0 55 
J 0
(4314 975);
DISPLAY 0.638298 (4314 975);
PAINT MONO (4314 975);
FORCEPROP 2 LAST ROOM VDDQ_KLM_PWR_VR
J 0
(3700 1050);
DISPLAY 1.361702 (3700 1050);
PAINT ORANGE (3700 1050);
DISPLAY INVISIBLE (3700 1050);
FORCEPROP 2 LAST CDS_LIB mstr_standard
J 0
(4100 975);
PAINT ORANGE (4100 975);
DISPLAY INVISIBLE (4100 975);
FORCEPROP 2 LAST PATH I63
J 0
(4525 1025);
DISPLAY 1.021277 (4525 1025);
PAINT ORANGE (4525 1025);
DISPLAY INVISIBLE (4525 1025);
FORCEPROP 1 LAST OFFPAGE TRUE
J 0
(4425 850);
DISPLAY 1.170213 (4425 850);
PAINT GREEN (4425 850);
DISPLAY INVISIBLE (4425 850);
FORCEPROP 1 LAST COMMENT_BODY TRUE
J 0
(4050 875);
DISPLAY 1.170213 (4050 875);
PAINT GREEN (4050 875);
DISPLAY INVISIBLE (4050 875);
FORCEADD OFFPAGE..3
(4100 1275);
FORCEPROP 2 LAST $XR11 235 
J 0
(4314 1167);
DISPLAY 0.638298 (4314 1167);
PAINT MONO (4314 1167);
FORCEPROP 2 LAST $XR10 223 
J 0
(4794 1203);
DISPLAY 0.638298 (4794 1203);
PAINT MONO (4794 1203);
FORCEPROP 2 LAST $XR9 218 
J 0
(4674 1203);
DISPLAY 0.638298 (4674 1203);
PAINT MONO (4674 1203);
FORCEPROP 2 LAST $XR8 215 
J 0
(4554 1203);
DISPLAY 0.638298 (4554 1203);
PAINT MONO (4554 1203);
FORCEPROP 2 LAST $XR7 213 
J 0
(4434 1203);
DISPLAY 0.638298 (4434 1203);
PAINT MONO (4434 1203);
FORCEPROP 2 LAST $XR6 211 
J 0
(4314 1203);
DISPLAY 0.638298 (4314 1203);
PAINT MONO (4314 1203);
FORCEPROP 2 LAST $XR5 206 
J 0
(4794 1239);
DISPLAY 0.638298 (4794 1239);
PAINT MONO (4794 1239);
FORCEPROP 2 LAST $XR4 201 
J 0
(4674 1239);
DISPLAY 0.638298 (4674 1239);
PAINT MONO (4674 1239);
FORCEPROP 2 LAST $XR3 194 
J 0
(4554 1239);
DISPLAY 0.638298 (4554 1239);
PAINT MONO (4554 1239);
FORCEPROP 2 LAST $XR2 193 
J 0
(4434 1239);
DISPLAY 0.638298 (4434 1239);
PAINT MONO (4434 1239);
FORCEPROP 2 LAST $XR1 159 
J 0
(4314 1239);
DISPLAY 0.638298 (4314 1239);
PAINT MONO (4314 1239);
FORCEPROP 2 LAST $XR0 138 
J 0
(4314 1275);
DISPLAY 0.638298 (4314 1275);
PAINT MONO (4314 1275);
FORCEPROP 2 LAST CDS_LIB mstr_standard
J 0
(4100 1275);
PAINT ORANGE (4100 1275);
DISPLAY INVISIBLE (4100 1275);
FORCEPROP 2 LAST ROOM VDDQ_KLM_PWR_VR
J 0
(3700 1350);
DISPLAY 1.361702 (3700 1350);
PAINT ORANGE (3700 1350);
DISPLAY INVISIBLE (3700 1350);
FORCEPROP 2 LAST PATH I64
J 0
(4325 1325);
DISPLAY 1.021277 (4325 1325);
PAINT ORANGE (4325 1325);
DISPLAY INVISIBLE (4325 1325);
FORCEPROP 1 LAST OFFPAGE TRUE
J 0
(4425 1150);
DISPLAY 1.170213 (4425 1150);
PAINT GREEN (4425 1150);
DISPLAY INVISIBLE (4425 1150);
FORCEPROP 1 LAST COMMENT_BODY TRUE
J 0
(4050 1175);
DISPLAY 1.170213 (4050 1175);
PAINT GREEN (4050 1175);
DISPLAY INVISIBLE (4050 1175);
FORCEADD OFFPAGE..1
R 2
(4100 1325);
FORCEPROP 2 LAST $XR11 223 
J 0
(4286 1361);
DISPLAY 0.638298 (4286 1361);
PAINT MONO (4286 1361);
FORCEPROP 2 LAST $XR10 218 
J 0
(4886 1289);
DISPLAY 0.638298 (4886 1289);
PAINT MONO (4886 1289);
FORCEPROP 2 LAST $XR9 215 
J 0
(4766 1289);
DISPLAY 0.638298 (4766 1289);
PAINT MONO (4766 1289);
FORCEPROP 2 LAST $XR8 206 
J 0
(4646 1289);
DISPLAY 0.638298 (4646 1289);
PAINT MONO (4646 1289);
FORCEPROP 2 LAST $XR7 201 
J 0
(4526 1289);
DISPLAY 0.638298 (4526 1289);
PAINT MONO (4526 1289);
FORCEPROP 2 LAST $XR6 194 
J 0
(4406 1289);
DISPLAY 0.638298 (4406 1289);
PAINT MONO (4406 1289);
FORCEPROP 2 LAST $XR5 193 
J 0
(4886 1325);
DISPLAY 0.638298 (4886 1325);
PAINT MONO (4886 1325);
FORCEPROP 2 LAST $XR4 235 
J 0
(4766 1325);
DISPLAY 0.638298 (4766 1325);
PAINT MONO (4766 1325);
FORCEPROP 2 LAST $XR3 213 
J 0
(4646 1325);
DISPLAY 0.638298 (4646 1325);
PAINT MONO (4646 1325);
FORCEPROP 2 LAST $XR2 211 
J 0
(4526 1325);
DISPLAY 0.638298 (4526 1325);
PAINT MONO (4526 1325);
FORCEPROP 2 LAST $XR1 159 
J 0
(4406 1325);
DISPLAY 0.638298 (4406 1325);
PAINT MONO (4406 1325);
FORCEPROP 2 LAST $XR0 138 
J 0
(4286 1325);
DISPLAY 0.638298 (4286 1325);
PAINT MONO (4286 1325);
FORCEPROP 2 LAST CDS_LIB mstr_standard
J 0
(4100 1325);
PAINT ORANGE (4100 1325);
DISPLAY INVISIBLE (4100 1325);
FORCEPROP 2 LAST ROOM VDDQ_KLM_PWR_VR
J 0
(3675 1400);
DISPLAY 1.361702 (3675 1400);
PAINT ORANGE (3675 1400);
DISPLAY INVISIBLE (3675 1400);
FORCEPROP 2 LAST PATH I65
J 0
(4300 1400);
DISPLAY 1.021277 (4300 1400);
PAINT ORANGE (4300 1400);
DISPLAY INVISIBLE (4300 1400);
FORCEPROP 1 LAST OFFPAGE TRUE
J 2
(3775 1200);
DISPLAY 1.170213 (3775 1200);
PAINT GREEN (3775 1200);
DISPLAY INVISIBLE (3775 1200);
FORCEPROP 1 LAST COMMENT_BODY TRUE
J 2
(3975 1225);
DISPLAY 1.170213 (3975 1225);
PAINT GREEN (3975 1225);
DISPLAY INVISIBLE (3975 1225);
FORCEADD OFFPAGE..2
(4100 1725);
FORCEPROP 2 LAST $XR2 145 
J 0
(4499 1725);
DISPLAY 0.638298 (4499 1725);
PAINT MONO (4499 1725);
FORCEPROP 2 LAST $XR1 119 
J 0
(4379 1725);
DISPLAY 0.638298 (4379 1725);
PAINT MONO (4379 1725);
FORCEPROP 2 LAST $XR0 94 
J 0
(4289 1725);
DISPLAY 0.638298 (4289 1725);
PAINT MONO (4289 1725);
FORCEPROP 2 LAST ROOM VDDQ_KLM_PWR_VR
J 0
(3675 1800);
DISPLAY 1.361702 (3675 1800);
PAINT ORANGE (3675 1800);
DISPLAY INVISIBLE (3675 1800);
FORCEPROP 2 LAST CDS_LIB mstr_standard
J 0
(4100 1725);
PAINT ORANGE (4100 1725);
DISPLAY INVISIBLE (4100 1725);
FORCEPROP 2 LAST PATH I66
J 0
(4500 1775);
DISPLAY 1.021277 (4500 1775);
PAINT ORANGE (4500 1775);
DISPLAY INVISIBLE (4500 1775);
FORCEPROP 1 LAST OFFPAGE TRUE
J 0
(4425 1600);
DISPLAY 1.170213 (4425 1600);
PAINT GREEN (4425 1600);
DISPLAY INVISIBLE (4425 1600);
FORCEPROP 1 LAST COMMENT_BODY TRUE
J 0
(4055 1630);
DISPLAY 1.170213 (4055 1630);
PAINT GREEN (4055 1630);
DISPLAY INVISIBLE (4055 1630);
FORCEADD OFFPAGE..2
(4100 1675);
FORCEPROP 2 LAST $XR2 55 
J 0
(4529 1675);
DISPLAY 0.638298 (4529 1675);
PAINT MONO (4529 1675);
FORCEPROP 2 LAST $XR1 223 
J 0
(4409 1675);
DISPLAY 0.638298 (4409 1675);
PAINT MONO (4409 1675);
FORCEPROP 2 LAST $XR0 193 
J 0
(4289 1675);
DISPLAY 0.638298 (4289 1675);
PAINT MONO (4289 1675);
FORCEPROP 2 LAST ROOM VDDQ_KLM_PWR_VR
J 0
(3675 1750);
DISPLAY 1.361702 (3675 1750);
PAINT ORANGE (3675 1750);
DISPLAY INVISIBLE (3675 1750);
FORCEPROP 2 LAST CDS_LIB mstr_standard
J 0
(4100 1675);
PAINT ORANGE (4100 1675);
DISPLAY INVISIBLE (4100 1675);
FORCEPROP 2 LAST PATH I67
J 0
(4550 1725);
DISPLAY 1.021277 (4550 1725);
PAINT ORANGE (4550 1725);
DISPLAY INVISIBLE (4550 1725);
FORCEPROP 1 LAST OFFPAGE TRUE
J 0
(4425 1550);
DISPLAY 1.170213 (4425 1550);
PAINT GREEN (4425 1550);
DISPLAY INVISIBLE (4425 1550);
FORCEPROP 1 LAST COMMENT_BODY TRUE
J 0
(4055 1580);
DISPLAY 1.170213 (4055 1580);
PAINT GREEN (4055 1580);
DISPLAY INVISIBLE (4055 1580);
FORCEADD OFFPAGE..2
(4100 1825);
FORCEPROP 2 LAST $XR0 197 
J 0
(4289 1825);
DISPLAY 0.638298 (4289 1825);
PAINT MONO (4289 1825);
FORCEPROP 2 LAST ROOM VDDQ_KLM_PWR_VR
J 0
(3675 1900);
DISPLAY 1.361702 (3675 1900);
PAINT ORANGE (3675 1900);
DISPLAY INVISIBLE (3675 1900);
FORCEPROP 2 LAST CDS_LIB mstr_standard
J 0
(4100 1825);
PAINT ORANGE (4100 1825);
DISPLAY INVISIBLE (4100 1825);
FORCEPROP 2 LAST PATH I68
J 0
(4300 1875);
DISPLAY 1.021277 (4300 1875);
PAINT ORANGE (4300 1875);
DISPLAY INVISIBLE (4300 1875);
FORCEPROP 1 LAST OFFPAGE TRUE
J 0
(4425 1700);
DISPLAY 1.170213 (4425 1700);
PAINT GREEN (4425 1700);
DISPLAY INVISIBLE (4425 1700);
FORCEPROP 1 LAST COMMENT_BODY TRUE
J 0
(4055 1730);
DISPLAY 1.170213 (4055 1730);
PAINT GREEN (4055 1730);
DISPLAY INVISIBLE (4055 1730);
FORCEADD PXM1310B..2
(1175 1075);
FORCEPROP 2 LASTPIN (1625 1525) $PN 18
J 0
(1635 1535);
DISPLAY 0.617021 (1635 1535);
PAINT ORANGE (1635 1535);
FORCEPROP 2 LASTPIN (725 1175) $PN 38
J 2
(715 1185);
DISPLAY 0.617021 (715 1185);
PAINT ORANGE (715 1185);
FORCEPROP 1 LAST PART_NUMBER H89186-001
J 0
(775 125);
DISPLAY 0.617021 (775 125);
PAINT BLUE (775 125);
FORCEPROP 2 LASTPIN (725 675) $PN 20
J 2
(715 685);
DISPLAY 0.617021 (715 685);
PAINT ORANGE (715 685);
FORCEPROP 2 LASTPIN (725 775) $PN 10
J 2
(715 785);
DISPLAY 0.617021 (715 785);
PAINT ORANGE (715 785);
FORCEPROP 2 LASTPIN (725 375) $PN 32
J 2
(715 385);
DISPLAY 0.617021 (715 385);
PAINT ORANGE (715 385);
FORCEPROP 2 LASTPIN (725 625) $PN 30
J 2
(715 635);
DISPLAY 0.617021 (715 635);
PAINT ORANGE (715 635);
FORCEPROP 2 LASTPIN (725 1425) $PN 22
J 2
(715 1435);
DISPLAY 0.617021 (715 1435);
PAINT ORANGE (715 1435);
FORCEPROP 2 LASTPIN (725 1375) $PN 24
J 2
(715 1385);
DISPLAY 0.617021 (715 1385);
PAINT ORANGE (715 1385);
FORCEPROP 2 LASTPIN (1625 375) $PN 41
J 0
(1635 385);
DISPLAY 0.617021 (1635 385);
PAINT ORANGE (1635 385);
FORCEPROP 2 LASTPIN (1625 975) $PN 16
J 0
(1635 985);
DISPLAY 0.617021 (1635 985);
PAINT ORANGE (1635 985);
FORCEPROP 2 LASTPIN (725 225) $PN 33
J 2
(715 235);
DISPLAY 0.617021 (715 235);
PAINT ORANGE (715 235);
FORCEPROP 2 LASTPIN (1625 1825) $PN 9
J 0
(1635 1835);
DISPLAY 0.617021 (1635 1835);
PAINT ORANGE (1635 1835);
FORCEPROP 2 LASTPIN (1625 1675) $PN 17
J 0
(1635 1685);
DISPLAY 0.617021 (1635 1685);
PAINT ORANGE (1635 1685);
FORCEPROP 2 LASTPIN (1625 1425) $PN 12
J 0
(1635 1435);
DISPLAY 0.617021 (1635 1435);
PAINT ORANGE (1635 1435);
FORCEPROP 2 LASTPIN (725 1825) $PN 39
J 2
(715 1835);
DISPLAY 0.617021 (715 1835);
PAINT ORANGE (715 1835);
FORCEPROP 2 LASTPIN (725 1725) $PN 15
J 2
(715 1735);
DISPLAY 0.617021 (715 1735);
PAINT ORANGE (715 1735);
FORCEPROP 2 LASTPIN (725 1625) $PN 21
J 2
(715 1635);
DISPLAY 0.617021 (715 1635);
PAINT ORANGE (715 1635);
FORCEPROP 2 LASTPIN (725 1575) $PN 23
J 2
(715 1585);
DISPLAY 0.617021 (715 1585);
PAINT ORANGE (715 1585);
FORCEPROP 2 LASTPIN (725 1525) $PN 25
J 2
(715 1535);
DISPLAY 0.617021 (715 1535);
PAINT ORANGE (715 1535);
FORCEPROP 2 LASTPIN (1625 1325) $PN 7
J 0
(1635 1335);
DISPLAY 0.617021 (1635 1335);
PAINT ORANGE (1635 1335);
FORCEPROP 2 LASTPIN (1625 1275) $PN 6
J 0
(1635 1285);
DISPLAY 0.617021 (1635 1285);
PAINT ORANGE (1635 1285);
FORCEPROP 2 LASTPIN (1625 1125) $PN 14
J 0
(1635 1135);
DISPLAY 0.617021 (1635 1135);
PAINT ORANGE (1635 1135);
FORCEPROP 2 LASTPIN (1625 1175) $PN 13
J 0
(1635 1185);
DISPLAY 0.617021 (1635 1185);
PAINT ORANGE (1635 1185);
FORCEPROP 2 LASTPIN (1625 1025) $PN 40
J 0
(1635 1035);
DISPLAY 0.617021 (1635 1035);
PAINT ORANGE (1635 1035);
FORCEPROP 2 LASTPIN (1625 825) $PN 1
J 0
(1635 835);
DISPLAY 0.617021 (1635 835);
PAINT ORANGE (1635 835);
FORCEPROP 2 LASTPIN (1625 675) $PN 3
J 0
(1635 685);
DISPLAY 0.617021 (1635 685);
PAINT ORANGE (1635 685);
FORCEPROP 2 LASTPIN (1625 725) $PN 4
J 0
(1635 735);
DISPLAY 0.617021 (1635 735);
PAINT ORANGE (1635 735);
FORCEPROP 2 LASTPIN (1625 775) $PN 5
J 0
(1635 785);
DISPLAY 0.617021 (1635 785);
PAINT ORANGE (1635 785);
FORCEPROP 2 LASTPIN (1625 475) $PN 2
J 0
(1635 485);
DISPLAY 0.617021 (1635 485);
PAINT ORANGE (1635 485);
FORCEPROP 2 LASTPIN (1625 275) $PN 27
J 0
(1635 285);
DISPLAY 0.617021 (1635 285);
PAINT ORANGE (1635 285);
FORCEPROP 2 LASTPIN (725 875) $PN 29
J 2
(715 885);
DISPLAY 0.617021 (715 885);
PAINT ORANGE (715 885);
FORCEPROP 2 LASTPIN (725 925) $PN 19
J 2
(715 935);
DISPLAY 0.617021 (715 935);
PAINT ORANGE (715 935);
FORCEPROP 2 LASTPIN (725 275) $PN 36
J 2
(715 285);
DISPLAY 0.617021 (715 285);
PAINT ORANGE (715 285);
FORCEPROP 2 LASTPIN (725 1325) $PN 26
J 2
(715 1335);
DISPLAY 0.617021 (715 1335);
PAINT ORANGE (715 1335);
FORCEPROP 2 LASTPIN (725 1225) $PN 37
J 2
(715 1235);
DISPLAY 0.617021 (715 1235);
PAINT ORANGE (715 1235);
FORCEPROP 2 LASTPIN (725 1075) $PN 35
J 2
(715 1085);
DISPLAY 0.617021 (715 1085);
PAINT ORANGE (715 1085);
FORCEPROP 2 LASTPIN (1625 1725) $PN 11
J 0
(1635 1735);
DISPLAY 0.617021 (1635 1735);
PAINT ORANGE (1635 1735);
FORCEPROP 1 LAST MATERIAL IC
J 0
(775 2000);
DISPLAY 0.617021 (775 2000);
PAINT SKYBLUE (775 2000);
FORCEPROP 2 LASTPIN (725 1025) $PN 34
J 2
(715 1035);
DISPLAY 0.617021 (715 1035);
PAINT ORANGE (715 1035);
FORCEPROP 2 LASTPIN (1625 525) $PN 28
J 0
(1635 535);
DISPLAY 0.617021 (1635 535);
PAINT ORANGE (1635 535);
FORCEPROP 1 LAST LOCATION EU1B1
J 0
(775 2050);
DISPLAY 0.617021 (775 2050);
PAINT AQUA (775 2050);
FORCEPROP 2 LASTPIN (725 425) $PN 31
J 2
(715 435);
DISPLAY 0.617021 (715 435);
PAINT ORANGE (715 435);
FORCEPROP 2 LASTPIN (725 525) $PN 8
J 2
(715 535);
DISPLAY 0.617021 (715 535);
PAINT ORANGE (715 535);
FORCEPROP 1 LAST PATH I69
J 0
(1275 2001);
PAINT WHITE (1275 2001);
DISPLAY INVISIBLE (1275 2001);
FORCEPROP 0 LAST CDS_SEC 1
J 0
(775 2100);
PAINT MONO (775 2100);
DISPLAY INVISIBLE (775 2100);
FORCEPROP 2 LAST SEC 1
J 0
(775 2100);
DISPLAY 0.680851 (775 2100);
PAINT MONO (775 2100);
DISPLAY INVISIBLE (775 2100);
FORCEPROP 2 LAST SEC_TYPE QFN
J 0
(775 2100);
DISPLAY 1.021277 (775 2100);
PAINT ORANGE (775 2100);
DISPLAY INVISIBLE (775 2100);
FORCEPROP 1 LAST PACK_TYPE QFN
J 0
(775 2100);
PAINT SKYBLUE (775 2100);
DISPLAY INVISIBLE (775 2100);
FORCEPROP 2 LAST CDS_LOCATION EU1B1
J 0
(775 2050);
PAINT WHITE (775 2050);
DISPLAY INVISIBLE (775 2050);
FORCEPROP 2 LAST CDS_LIB mstr_controller
J 0
(1175 1075);
PAINT ORANGE (1175 1075);
DISPLAY INVISIBLE (1175 1075);
FORCEPROP 1 LAST CDS_LMAN_SYM_OUTLINE -400,900,400,-900
J 0
(1175 1075);
DISPLAY 0.468085 (1175 1075);
PAINT GREEN (1175 1075);
DISPLAY INVISIBLE (1175 1075);
FORCEADD OFFPAGE..1
(-2500 1375);
FORCEPROP 2 LAST $XR0 227 
J 0
(-2752 1375);
DISPLAY 0.638298 (-2752 1375);
PAINT MONO (-2752 1375);
FORCEPROP 2 LAST ROOM VDDQ_KLM_PWR_VR
J 0
(-3050 1450);
DISPLAY 1.361702 (-3050 1450);
PAINT ORANGE (-3050 1450);
DISPLAY INVISIBLE (-3050 1450);
FORCEPROP 2 LAST CDS_LIB mstr_standard
J 0
(-2500 1375);
PAINT ORANGE (-2500 1375);
DISPLAY INVISIBLE (-2500 1375);
FORCEPROP 2 LAST PATH I7
J 0
(-2750 1425);
DISPLAY 1.021277 (-2750 1425);
PAINT ORANGE (-2750 1425);
DISPLAY INVISIBLE (-2750 1425);
FORCEPROP 1 LAST OFFPAGE TRUE
J 0
(-2175 1250);
DISPLAY 1.170213 (-2175 1250);
PAINT GREEN (-2175 1250);
DISPLAY INVISIBLE (-2175 1250);
FORCEPROP 1 LAST COMMENT_BODY TRUE
J 0
(-2375 1275);
DISPLAY 1.170213 (-2375 1275);
PAINT GREEN (-2375 1275);
DISPLAY INVISIBLE (-2375 1275);
FORCEADD RES..2
(-925 2850);
FORCEPROP 1 LAST PACK_TYPE 0402
J 0
(-885 2675);
DISPLAY 0.617021 (-885 2675);
PAINT SKYBLUE (-885 2675);
FORCEPROP 1 LAST LOCATION R9M6
J 0
(-880 2975);
DISPLAY 0.617021 (-880 2975);
PAINT AQUA (-880 2975);
FORCEPROP 1 LAST VALUE 49.9
J 0
(-880 2925);
DISPLAY 0.617021 (-880 2925);
PAINT SKYBLUE (-880 2925);
FORCEPROP 1 LASTPIN (-925 2950) $PN 1
J 0
(-920 2912);
DISPLAY 0.617021 (-920 2912);
PAINT ORANGE (-920 2912);
FORCEPROP 1 LASTPIN (-925 2750) $PN 2
J 0
(-920 2760);
DISPLAY 0.617021 (-920 2760);
PAINT ORANGE (-920 2760);
FORCEPROP 1 LAST PART_NUMBER G21796-047
J 0
(-885 2725);
DISPLAY 0.617021 (-885 2725);
PAINT BLUE (-885 2725);
FORCEPROP 1 LAST TOLERANCE 1%
J 0
(-880 2875);
DISPLAY 0.617021 (-880 2875);
PAINT SKYBLUE (-880 2875);
FORCEPROP 1 LAST MATERIAL EMPTY
J 0
(-885 2775);
DISPLAY 0.617021 (-885 2775);
PAINT RED (-885 2775);
FORCEPROP 1 LAST WATTAGE 1/16W
J 0
(-885 2825);
DISPLAY 0.617021 (-885 2825);
PAINT SKYBLUE (-885 2825);
FORCEPROP 2 LAST SEC_TYPE 0402
J 0
(-875 3100);
DISPLAY 1.021277 (-875 3100);
PAINT ORANGE (-875 3100);
DISPLAY INVISIBLE (-875 3100);
FORCEPROP 2 LAST SEC 1
J 0
(-875 3100);
PAINT MONO (-875 3100);
DISPLAY INVISIBLE (-875 3100);
FORCEPROP 2 LAST ROOM VDDQ_GHJ_PWR_VR
J 0
(-875 3025);
DISPLAY 1.361702 (-875 3025);
PAINT ORANGE (-875 3025);
DISPLAY INVISIBLE (-875 3025);
FORCEPROP 2 LAST CDS_LIB mstr_discrete
J 0
(-925 2850);
PAINT ORANGE (-925 2850);
DISPLAY INVISIBLE (-925 2850);
FORCEPROP 0 LAST CDS_SEC 1
J 0
(-875 3025);
PAINT MONO (-875 3025);
DISPLAY INVISIBLE (-875 3025);
FORCEPROP 1 LAST PATH I70
J 0
(-875 3025);
DISPLAY 0.978723 (-875 3025);
PAINT WHITE (-875 3025);
DISPLAY INVISIBLE (-875 3025);
FORCEPROP 2 LAST CDS_LOCATION R9M6
J 0
(-880 2975);
DISPLAY 0.617021 (-880 2975);
PAINT AQUA (-880 2975);
DISPLAY INVISIBLE (-880 2975);
FORCEADD RES..2
(-50 -600);
FORCEPROP 1 LAST LOCATION R1B12
J 0
(-5 -475);
DISPLAY 0.617021 (-5 -475);
PAINT AQUA (-5 -475);
FORCEPROP 1 LAST TOLERANCE 1.0%
J 0
(-5 -575);
DISPLAY 0.617021 (-5 -575);
PAINT SKYBLUE (-5 -575);
FORCEPROP 1 LAST VALUE 16K
J 0
(-5 -525);
DISPLAY 0.617021 (-5 -525);
PAINT SKYBLUE (-5 -525);
FORCEPROP 1 LAST PACK_TYPE 0402
J 0
(-10 -775);
DISPLAY 0.617021 (-10 -775);
PAINT SKYBLUE (-10 -775);
FORCEPROP 1 LAST PART_NUMBER G21796-317
J 0
(-10 -725);
DISPLAY 0.617021 (-10 -725);
PAINT BLUE (-10 -725);
FORCEPROP 1 LAST WATTAGE 1/16W
J 0
(-10 -625);
DISPLAY 0.617021 (-10 -625);
PAINT SKYBLUE (-10 -625);
FORCEPROP 1 LAST MATERIAL CHIP
J 0
(-10 -675);
DISPLAY 0.617021 (-10 -675);
PAINT SKYBLUE (-10 -675);
FORCEPROP 0 LAST ROOM VDDQ_ABC_PWR_VR
J 0
(0 -375);
DISPLAY 1.021277 (0 -375);
PAINT ORANGE (0 -375);
DISPLAY INVISIBLE (0 -375);
FORCEPROP 1 LAST PATH I72
J 0
(0 -425);
DISPLAY 0.978723 (0 -425);
PAINT WHITE (0 -425);
DISPLAY INVISIBLE (0 -425);
FORCEPROP 2 LAST CDS_LIB mstr_discrete
J 0
(-50 -600);
DISPLAY INVISIBLE (-50 -600);
FORCEPROP 1 LASTPIN (-50 -700) $PN 2
J 0
(-45 -690);
DISPLAY 0.787234 (-45 -690);
PAINT ORANGE (-45 -690);
DISPLAY INVISIBLE (-45 -690);
FORCEPROP 1 LASTPIN (-50 -500) $PN 1
J 0
(-45 -538);
DISPLAY 0.787234 (-45 -538);
PAINT ORANGE (-45 -538);
DISPLAY INVISIBLE (-45 -538);
FORCEADD RES..2
(325 -600);
FORCEPROP 1 LAST PART_NUMBER G21796-043
J 0
(365 -725);
DISPLAY 0.617021 (365 -725);
PAINT BLUE (365 -725);
FORCEPROP 1 LAST PACK_TYPE 0402
J 0
(365 -775);
DISPLAY 0.617021 (365 -775);
PAINT SKYBLUE (365 -775);
FORCEPROP 1 LAST TOLERANCE 1%
J 0
(370 -575);
DISPLAY 0.617021 (370 -575);
PAINT SKYBLUE (370 -575);
FORCEPROP 1 LAST MATERIAL CHIP
J 0
(365 -675);
DISPLAY 0.617021 (365 -675);
PAINT SKYBLUE (365 -675);
FORCEPROP 1 LASTPIN (325 -700) $PN 2
J 0
(330 -690);
DISPLAY 0.617021 (330 -690);
PAINT WHITE (330 -690);
FORCEPROP 1 LAST WATTAGE 1/16W
J 0
(365 -625);
DISPLAY 0.617021 (365 -625);
PAINT SKYBLUE (365 -625);
FORCEPROP 1 LAST VALUE 3.16K
J 0
(370 -525);
DISPLAY 0.617021 (370 -525);
PAINT SKYBLUE (370 -525);
FORCEPROP 1 LASTPIN (325 -500) $PN 1
J 0
(330 -538);
DISPLAY 0.617021 (330 -538);
PAINT WHITE (330 -538);
FORCEPROP 1 LAST LOCATION R1B15
J 0
(370 -475);
DISPLAY 0.617021 (370 -475);
PAINT AQUA (370 -475);
FORCEPROP 2 LAST CDS_LOCATION R1B15
J 0
(370 -475);
DISPLAY 0.617021 (370 -475);
PAINT AQUA (370 -475);
DISPLAY INVISIBLE (370 -475);
FORCEPROP 2 LAST SEC_TYPE 0402
J 0
(375 -375);
DISPLAY 1.021277 (375 -375);
PAINT ORANGE (375 -375);
DISPLAY INVISIBLE (375 -375);
FORCEPROP 0 LAST SEC 1
J 0
(375 -325);
DISPLAY 0.680851 (375 -325);
PAINT MONO (375 -325);
DISPLAY INVISIBLE (375 -325);
FORCEPROP 0 LAST ROOM PVCCIN_CPU1_VR
J 0
(375 -375);
DISPLAY 1.021277 (375 -375);
PAINT ORANGE (375 -375);
DISPLAY INVISIBLE (375 -375);
FORCEPROP 2 LAST CDS_LIB mstr_discrete
J 0
(325 -600);
PAINT ORANGE (325 -600);
DISPLAY INVISIBLE (325 -600);
FORCEPROP 0 LAST CDS_SEC 1
J 0
(375 -425);
DISPLAY INVISIBLE (375 -425);
FORCEPROP 1 LAST PATH I73
J 0
(375 -425);
DISPLAY 0.978723 (375 -425);
PAINT WHITE (375 -425);
DISPLAY INVISIBLE (375 -425);
FORCEADD RES..1
(2950 1175);
FORCEPROP 1 LAST PACK_TYPE 0402
J 0
(3300 1175);
DISPLAY 0.617021 (3300 1175);
PAINT SKYBLUE (3300 1175);
FORCEPROP 1 LASTPIN (2850 1175) $PN 1
J 0
(2862 1187);
DISPLAY 0.617021 (2862 1187);
PAINT WHITE (2862 1187);
FORCEPROP 1 LAST LOCATION R12W34
J 0
(2450 1175);
DISPLAY 0.617021 (2450 1175);
PAINT AQUA (2450 1175);
FORCEPROP 1 LASTPIN (3050 1175) $PN 2
J 0
(3012 1187);
DISPLAY 0.617021 (3012 1187);
PAINT WHITE (3012 1187);
FORCEPROP 1 LAST VALUE 0.0
J 0
(3075 1175);
DISPLAY 0.617021 (3075 1175);
PAINT SKYBLUE (3075 1175);
FORCEPROP 1 LAST TOLERANCE 5%
J 0
(3150 1175);
DISPLAY 0.617021 (3150 1175);
PAINT SKYBLUE (3150 1175);
FORCEPROP 1 LAST WATTAGE 1/16W
J 0
(3400 1175);
DISPLAY 0.510638 (3400 1175);
PAINT SKYBLUE (3400 1175);
FORCEPROP 1 LAST PART_NUMBER G21497-005
J 0
(2625 1175);
DISPLAY 0.617021 (2625 1175);
PAINT BLUE (2625 1175);
FORCEPROP 2 LAST SEC 1
J 0
(2900 1400);
DISPLAY 0.680851 (2900 1400);
PAINT MONO (2900 1400);
DISPLAY INVISIBLE (2900 1400);
FORCEPROP 2 LAST SEC_TYPE 0402
J 0
(2900 1400);
DISPLAY 1.021277 (2900 1400);
PAINT ORANGE (2900 1400);
DISPLAY INVISIBLE (2900 1400);
FORCEPROP 2 LAST ROOM CPU0
J 0
(2900 1325);
PAINT PEACH (2900 1325);
DISPLAY INVISIBLE (2900 1325);
FORCEPROP 1 LAST MATERIAL CHIP
J 0
(3100 1075);
DISPLAY 0.510638 (3100 1075);
PAINT SKYBLUE (3100 1075);
DISPLAY INVISIBLE (3100 1075);
FORCEPROP 2 LAST BOM_COST PROC_SIDEBAND
J 0
(2950 1175);
PAINT MONO (2950 1175);
DISPLAY INVISIBLE (2950 1175);
FORCEPROP 2 LAST CDS_LIB mstr_discrete
J 0
(2950 1175);
DISPLAY 1.340426 (2950 1175);
PAINT ORANGE (2950 1175);
DISPLAY INVISIBLE (2950 1175);
FORCEPROP 0 LAST CDS_SEC 1
J 0
(3250 1225);
DISPLAY INVISIBLE (3250 1225);
FORCEPROP 1 LAST PATH I74
J 0
(2900 1325);
DISPLAY 0.978723 (2900 1325);
PAINT WHITE (2900 1325);
DISPLAY INVISIBLE (2900 1325);
FORCEPROP 2 LAST CDS_LOCATION R12W34
J 0
(2475 1175);
DISPLAY 0.617021 (2475 1175);
PAINT AQUA (2475 1175);
DISPLAY INVISIBLE (2475 1175);
FORCEADD RES..2
(3250 2350);
FORCEPROP 1 LAST VALUE 2.26K
J 0
(3295 2425);
DISPLAY 0.617021 (3295 2425);
PAINT SKYBLUE (3295 2425);
FORCEPROP 1 LAST TOLERANCE 1.0%
J 0
(3295 2375);
DISPLAY 0.617021 (3295 2375);
PAINT SKYBLUE (3295 2375);
FORCEPROP 1 LAST WATTAGE 1/16W
J 0
(3290 2325);
DISPLAY 0.617021 (3290 2325);
PAINT SKYBLUE (3290 2325);
FORCEPROP 1 LAST MATERIAL CHIP
J 0
(3290 2275);
DISPLAY 0.617021 (3290 2275);
PAINT SKYBLUE (3290 2275);
FORCEPROP 1 LAST LOCATION R1B13
J 0
(3295 2475);
DISPLAY 0.617021 (3295 2475);
PAINT AQUA (3295 2475);
FORCEPROP 1 LAST PACK_TYPE 0402
J 0
(3290 2175);
DISPLAY 0.617021 (3290 2175);
PAINT SKYBLUE (3290 2175);
FORCEPROP 1 LAST PART_NUMBER G21796-311
J 0
(3290 2225);
DISPLAY 0.617021 (3290 2225);
PAINT BLUE (3290 2225);
FORCEPROP 0 LAST SKU B
J 0
(3300 2575);
DISPLAY 1.021277 (3300 2575);
PAINT ORANGE (3300 2575);
DISPLAY INVISIBLE (3300 2575);
FORCEPROP 0 LAST ROOM SMBUS
J 0
(3300 2575);
DISPLAY 1.021277 (3300 2575);
PAINT ORANGE (3300 2575);
DISPLAY INVISIBLE (3300 2575);
FORCEPROP 0 LAST BOM_COST SM_CONTROLLER
J 0
(3300 2675);
DISPLAY 1.021277 (3300 2675);
PAINT ORANGE (3300 2675);
DISPLAY INVISIBLE (3300 2675);
FORCEPROP 1 LAST PATH I75
J 0
(3300 2525);
DISPLAY 0.978723 (3300 2525);
PAINT WHITE (3300 2525);
DISPLAY INVISIBLE (3300 2525);
FORCEPROP 2 LAST CDS_LIB mstr_discrete
J 0
(3250 2350);
DISPLAY INVISIBLE (3250 2350);
FORCEPROP 1 LASTPIN (3250 2250) $PN 2
J 0
(3255 2260);
DISPLAY 0.787234 (3255 2260);
PAINT ORANGE (3255 2260);
DISPLAY INVISIBLE (3255 2260);
FORCEPROP 1 LASTPIN (3250 2450) $PN 1
J 0
(3255 2412);
DISPLAY 0.787234 (3255 2412);
PAINT ORANGE (3255 2412);
DISPLAY INVISIBLE (3255 2412);
FORCEADD OFFPAGE..1
(-2500 1575);
FORCEPROP 2 LAST $XR0 227 
J 0
(-2752 1575);
DISPLAY 0.638298 (-2752 1575);
PAINT MONO (-2752 1575);
FORCEPROP 2 LAST ROOM VDDQ_KLM_PWR_VR
J 0
(-3050 1650);
DISPLAY 1.361702 (-3050 1650);
PAINT ORANGE (-3050 1650);
DISPLAY INVISIBLE (-3050 1650);
FORCEPROP 2 LAST CDS_LIB mstr_standard
J 0
(-2500 1575);
PAINT ORANGE (-2500 1575);
DISPLAY INVISIBLE (-2500 1575);
FORCEPROP 2 LAST PATH I8
J 0
(-2750 1625);
DISPLAY 1.021277 (-2750 1625);
PAINT ORANGE (-2750 1625);
DISPLAY INVISIBLE (-2750 1625);
FORCEPROP 1 LAST OFFPAGE TRUE
J 0
(-2175 1450);
DISPLAY 1.170213 (-2175 1450);
PAINT GREEN (-2175 1450);
DISPLAY INVISIBLE (-2175 1450);
FORCEPROP 1 LAST COMMENT_BODY TRUE
J 0
(-2375 1475);
DISPLAY 1.170213 (-2375 1475);
PAINT GREEN (-2375 1475);
DISPLAY INVISIBLE (-2375 1475);
FORCEADD OFFPAGE..1
(-2500 1425);
FORCEPROP 2 LAST $XR0 227 
J 0
(-2752 1425);
DISPLAY 0.638298 (-2752 1425);
PAINT MONO (-2752 1425);
FORCEPROP 2 LAST ROOM VDDQ_KLM_PWR_VR
J 0
(-3050 1500);
DISPLAY 1.361702 (-3050 1500);
PAINT ORANGE (-3050 1500);
DISPLAY INVISIBLE (-3050 1500);
FORCEPROP 2 LAST CDS_LIB mstr_standard
J 0
(-2500 1425);
PAINT ORANGE (-2500 1425);
DISPLAY INVISIBLE (-2500 1425);
FORCEPROP 2 LAST PATH I9
J 0
(-2750 1475);
DISPLAY 1.021277 (-2750 1475);
PAINT ORANGE (-2750 1475);
DISPLAY INVISIBLE (-2750 1475);
FORCEPROP 1 LAST OFFPAGE TRUE
J 0
(-2175 1300);
DISPLAY 1.170213 (-2175 1300);
PAINT GREEN (-2175 1300);
DISPLAY INVISIBLE (-2175 1300);
FORCEPROP 1 LAST COMMENT_BODY TRUE
J 0
(-2375 1325);
DISPLAY 1.170213 (-2375 1325);
PAINT GREEN (-2375 1325);
DISPLAY INVISIBLE (-2375 1325);
FORCEADD DNS..2
(3755 2070);
PAINT RED (3755 2070);
FORCEPROP 2 LAST CDS_LIB mstr_misc
J 0
(3755 2070);
PAINT ORANGE (3755 2070);
DISPLAY INVISIBLE (3755 2070);
FORCEPROP 1 LAST COMMENT_BODY TRUE
R 1
J 0
(3830 1845);
DISPLAY 0.872340 (3830 1845);
PAINT GREEN (3830 1845);
DISPLAY INVISIBLE (3830 1845);
FORCEADD INTEL_CORP_BPAGE..1
(5000 -1575);
FORCEPROP 1 LAST CDS_CON_LAST_MODIFIED Fri Jun 16 17:49:21 2017
J 0
(3575 -1250);
DISPLAY 0.744681 (3575 -1250);
PAINT GREEN (3575 -1250);
DISPLAY INVISIBLE (3575 -1250);
FORCEPROP 1 LAST CUSTOM_TXT_CDS <CURRENT_DESIGN_SHEET> OF <TOTAL_DESIGN_SHEETS>
J 0
(4500 -1550);
PAINT ORANGE (4500 -1550);
FORCEPROP 1 LAST CUSTOM_TXT_CDS <CON_LAST_MODIFIED>
J 0
(1000 -1475);
PAINT ORANGE (1000 -1475);
FORCEPROP 2 LAST CUSTOM_TXT_CDS <XR_PAGE_TITLE>
J 0
(-2890 3675);
DISPLAY 0.638298 (-2890 3675);
PAINT PINK (-2890 3675);
DISPLAY INVISIBLE (-2890 3675);
FORCEPROP 1 LAST SCH_TITLE VDDQ KLM_VR (1 OF 3)
J 0
(-2975 -1550);
DISPLAY 1.212766 (-2975 -1550);
PAINT ORANGE (-2975 -1550);
FORCEPROP 2 LAST ROOM VDDQ_KLM_PWR_VR
J 0
(4550 3575);
DISPLAY 0.744681 (4550 3575);
PAINT ORANGE (4550 3575);
DISPLAY INVISIBLE (4550 3575);
FORCEPROP 2 LAST CDS_LIB mstr_symbols
J 0
(5000 -1575);
DISPLAY 0.744681 (5000 -1575);
PAINT ORANGE (5000 -1575);
DISPLAY INVISIBLE (5000 -1575);
FORCEPROP 2 LAST PAGE_BORDER TRUE
J 0
(-2890 3675);
DISPLAY 0.638298 (-2890 3675);
PAINT PINK (-2890 3675);
DISPLAY INVISIBLE (-2890 3675);
FORCEPROP 1 LAST COMMENT_BODY TRUE
J 0
(5012 -1563);
DISPLAY 0.340426 (5012 -1563);
PAINT GREEN (5012 -1563);
DISPLAY INVISIBLE (5012 -1563);
FORCEPROP 2 LAST CDS_XR_PAGE_TITLE CR-226 : @BASEBOARD_FAB2_LIB.BASEBOARD_FAB2(SCH_1):PAGE226
J 0
(-2890 3675);
DISPLAY 0.638298 (-2890 3675);
PAINT PINK (-2890 3675);
DISPLAY INVISIBLE (-2890 3675);
FORCEADD DNS..2
(2955 1070);
PAINT RED (2955 1070);
FORCEPROP 2 LAST CDS_LIB mstr_misc
J 0
(2955 1070);
PAINT ORANGE (2955 1070);
DISPLAY INVISIBLE (2955 1070);
FORCEPROP 1 LAST COMMENT_BODY TRUE
R 1
J 0
(3030 845);
DISPLAY 0.872340 (3030 845);
PAINT GREEN (3030 845);
DISPLAY INVISIBLE (3030 845);
FORCEADD DESIGN_NOTE..1
(650 0);
FORCEPROP 0 LAST L1 SMBUS ADDRESS: 0XA4
J 0
(450 -125);
DISPLAY 1.021277 (450 -125);
PAINT VIOLET (450 -125);
FORCEPROP 2 LAST CDS_LIB mstr_symbols
J 0
(650 0);
PAINT ORANGE (650 0);
DISPLAY INVISIBLE (650 0);
FORCEPROP 1 LAST COMMENT_BODY TRUE
J 0
(675 100);
DISPLAY 0.978723 (675 100);
PAINT ORANGE (675 100);
DISPLAY INVISIBLE (675 100);
FORCEADD DNS..2
(-170 2845);
PAINT RED (-170 2845);
FORCEPROP 2 LAST CDS_LIB mstr_misc
J 0
(-170 2845);
PAINT ORANGE (-170 2845);
DISPLAY INVISIBLE (-170 2845);
FORCEPROP 1 LAST COMMENT_BODY TRUE
R 1
J 0
(-95 2620);
DISPLAY 0.872340 (-95 2620);
PAINT GREEN (-95 2620);
DISPLAY INVISIBLE (-95 2620);
FORCEADD DNS..2
(-920 2845);
PAINT RED (-920 2845);
FORCEPROP 2 LAST CDS_LIB mstr_misc
J 0
(-920 2845);
PAINT ORANGE (-920 2845);
DISPLAY INVISIBLE (-920 2845);
FORCEPROP 1 LAST COMMENT_BODY TRUE
R 1
J 0
(-845 2620);
DISPLAY 0.872340 (-845 2620);
PAINT GREEN (-845 2620);
DISPLAY INVISIBLE (-845 2620);
FORCEADD DNS..2
(2955 1545);
PAINT RED (2955 1545);
FORCEPROP 2 LAST CDS_LIB mstr_misc
J 0
(2955 1545);
PAINT ORANGE (2955 1545);
DISPLAY INVISIBLE (2955 1545);
FORCEPROP 1 LAST COMMENT_BODY TRUE
R 1
J 0
(3030 1320);
DISPLAY 0.872340 (3030 1320);
PAINT GREEN (3030 1320);
DISPLAY INVISIBLE (3030 1320);
FORCEADD DESIGN_NOTE..1
(3400 3350);
PAINT PURPLE (3400 3350);
FORCEPROP 0 LAST L1 SVID ADDRESS
J 0
(3200 3225);
PAINT VIOLET (3200 3225);
FORCEPROP 0 LAST L2 PVDDQ_KLM: 0X02(BUS #2)
J 0
(3205 3140);
DISPLAY 1.021277 (3205 3140);
PAINT VIOLET (3205 3140);
FORCEPROP 2 LAST CDS_LIB mstr_symbols
J 0
(3400 3350);
PAINT MONO (3400 3350);
DISPLAY INVISIBLE (3400 3350);
FORCEPROP 2 LAST BOM_COST VDDQ_KLM_VR
J 0
(3200 3300);
PAINT MONO (3200 3300);
DISPLAY INVISIBLE (3200 3300);
FORCEPROP 2 LAST ROOM VDDQ_KLM_PWR_VR
J 0
(3200 3300);
PAINT MONO (3200 3300);
DISPLAY INVISIBLE (3200 3300);
FORCEPROP 1 LAST COMMENT_BODY TRUE
J 0
(3425 3450);
DISPLAY 1.319149 (3425 3450);
PAINT GREEN (3425 3450);
DISPLAY INVISIBLE (3425 3450);
WIRE 16 -1 (-925 2950)(-925 3150);
WIRE 16 -1 (-225 -625)(-225 -75);
WIRE 16 -1 (3100 -700)(3100 -625);
WIRE 16 -1 (3500 -700)(3500 -625);
WIRE 16 -1 (-50 -800)(-50 -700);
WIRE 16 -1 (-150 375)(-150 175);
WIRE 16 -1 (725 375)(-150 375);
WIRE 16 -1 (325 -800)(325 -700);
WIRE 16 -1 (1750 150)(1750 275);
WIRE 16 -1 (1750 375)(1750 275);
WIRE 16 -1 (1625 275)(1750 275);
WIRE 16 -1 (1625 375)(1750 375);
WIRE 16 -1 (675 2225)(675 2275);
WIRE 16 -1 (250 3100)(250 3150);
WIRE 16 -1 (-175 3100)(250 3100);
WIRE 16 -1 (575 3100)(250 3100);
WIRE 16 -1 (575 2925)(575 3100);
WIRE 16 -1 (-175 2950)(-175 3100);
WIRE 16 -1 (1275 2225)(1275 2275);
WIRE 16 -1 (2650 175)(2650 50);
WIRE 16 -1 (2200 2825)(2200 2950);
WIRE 16 -1 (2200 2825)(2100 2825);
WIRE 16 -1 (3250 2825)(2200 2825);
WIRE 16 -1 (3250 2450)(3250 2825);
WIRE 16 -1 (1825 2825)(2100 2825);
WIRE 16 -1 (2100 2450)(2100 2825);
WIRE 16 -1 (1825 2450)(1825 2825);
WIRE 16 -1 (3750 2175)(3750 2250);
WIRE 16 -1 (400 1725)(725 1725);
WIRE 16 -1 (400 2350)(400 1725);
WIRE 16 -1 (-450 2350)(400 2350);
FORCEPROP 2 LAST SIG_NAME SVID_CLK_PVDDQ_KLM
J 0
(-90 2365);
DISPLAY 0.617021 (-90 2365);
PAINT ORANGE (-90 2365);
FORCEPROP 2 LASTPROP $XRERR UNIQUE?
J 0
(-330 2365);
DISPLAY 0.638298 (-330 2365);
PAINT MONO (-330 2365);
DISPLAY INVISIBLE (-330 2365);
WIRE 3 682 (-2100 1850)(-1850 1850);
WIRE 3 682 (-2100 2300)(-2100 1850);
WIRE 3 682 (-1850 2250)(-1850 1850);
WIRE 3 682 (-400 2250)(-1850 2250);
WIRE 3 682 (-2100 2300)(-400 2300);
WIRE 3 682 (-400 2300)(-400 2250);
WIRE 16 -1 (2225 1675)(1625 1675);
FORCEPROP 2 LAST SIG_NAME SVID_ALERT_PVDDQ_KLM
J 0
(1725 1690);
DISPLAY 0.617021 (1725 1690);
PAINT ORANGE (1725 1690);
FORCEPROP 2 LASTPROP $XRERR UNIQUE?
J 0
(1485 1690);
DISPLAY 0.638298 (1485 1690);
PAINT MONO (1485 1690);
DISPLAY INVISIBLE (1485 1690);
WIRE 16 -1 (4050 1025)(1625 1025);
FORCEPROP 2 LAST SIG_NAME VR_PVDDQ_KLM_VD12
J 0
(3360 1040);
DISPLAY 0.617021 (3360 1040);
PAINT ORANGE (3360 1040);
WIRE 16 -1 (-50 275)(725 275);
WIRE 16 -1 (-50 -500)(-50 275);
FORCEPROP 0 LAST SIG_NAME VR_PVDDQ_KLM_XADDR1
R 1
J 0
(-60 -290);
DISPLAY 0.617021 (-60 -290);
PAINT ORANGE (-60 -290);
FORCEPROP 2 LASTPROP $XRERR UNIQUE?
J 0
(-300 -290);
DISPLAY 0.638298 (-300 -290);
PAINT MONO (-300 -290);
DISPLAY INVISIBLE (-300 -290);
WIRE 16 -1 (1625 1125)(2850 1125);
FORCEPROP 2 LAST SIG_NAME NC_PVDDQ_KLM_GP1
J 0
(1725 1140);
DISPLAY 0.617021 (1725 1140);
PAINT ORANGE (1725 1140);
FORCEPROP 2 LASTPROP $XRERR UNIQUE?
J 0
(1485 1140);
DISPLAY 0.638298 (1485 1140);
PAINT MONO (1485 1140);
DISPLAY INVISIBLE (1485 1140);
WIRE 16 -1 (1625 1175)(2850 1175);
FORCEPROP 2 LAST SIG_NAME PU_VR_PVDDQ_KLM_FAULT1
J 0
(1710 1190);
DISPLAY 0.617021 (1710 1190);
PAINT ORANGE (1710 1190);
FORCEPROP 2 LASTPROP $XRERR UNIQUE?
J 0
(1470 1190);
DISPLAY 0.638298 (1470 1190);
PAINT MONO (1470 1190);
DISPLAY INVISIBLE (1470 1190);
WIRE 16 -1 (325 225)(725 225);
WIRE 16 -1 (325 -500)(325 225);
FORCEPROP 0 LAST SIG_NAME VR_PVDDQ_KLM_XADDR2
R 1
J 0
(315 -340);
DISPLAY 0.617021 (315 -340);
PAINT ORANGE (315 -340);
FORCEPROP 2 LASTPROP $XRERR UNIQUE?
J 0
(75 -340);
DISPLAY 0.638298 (75 -340);
PAINT MONO (75 -340);
DISPLAY INVISIBLE (75 -340);
WIRE 16 -1 (1625 975)(2425 975);
FORCEPROP 2 LAST SIG_NAME SVID_VDIO_PVDDQ_KLM
J 0
(1725 990);
DISPLAY 0.617021 (1725 990);
PAINT ORANGE (1725 990);
FORCEPROP 2 LASTPROP $XRERR UNIQUE?
J 0
(1485 990);
DISPLAY 0.638298 (1485 990);
PAINT MONO (1485 990);
DISPLAY INVISIBLE (1485 990);
WIRE 16 -1 (4050 1325)(1625 1325);
FORCEPROP 2 LAST SIG_NAME SMB_VR_STBY_LVC3_SCL
J 0
(2685 1340);
DISPLAY 0.617021 (2685 1340);
PAINT ORANGE (2685 1340);
WIRE 16 -1 (4050 1275)(1625 1275);
FORCEPROP 2 LAST SIG_NAME SMB_VR_STBY_LVC3_SDA
J 0
(2685 1290);
DISPLAY 0.617021 (2685 1290);
PAINT ORANGE (2685 1290);
WIRE 16 -1 (1625 725)(4050 725);
FORCEPROP 2 LAST SIG_NAME VR_PVDDQ_KLM_PWM2
J 0
(3350 740);
DISPLAY 0.617021 (3350 740);
PAINT ORANGE (3350 740);
WIRE 16 -1 (4050 775)(1625 775);
FORCEPROP 2 LAST SIG_NAME VR_PVDDQ_KLM_PWM1
J 0
(3350 790);
DISPLAY 0.617021 (3350 790);
PAINT ORANGE (3350 790);
WIRE 16 -1 (1625 1525)(2850 1525);
FORCEPROP 2 LAST SIG_NAME NC_PVDDQ_KLM_GP0
J 0
(1750 1540);
DISPLAY 0.617021 (1750 1540);
PAINT ORANGE (1750 1540);
FORCEPROP 2 LASTPROP $XRERR UNIQUE?
J 0
(1510 1540);
DISPLAY 0.638298 (1510 1540);
PAINT MONO (1510 1540);
DISPLAY INVISIBLE (1510 1540);
WIRE 16 -1 (3050 1125)(3250 1125);
WIRE 16 -1 (3250 1175)(3050 1175);
WIRE 16 -1 (3250 1125)(3250 1175);
WIRE 16 -1 (3050 1525)(3250 1525);
WIRE 16 -1 (3250 1175)(3250 1525);
WIRE 16 -1 (3250 1525)(3250 1825);
WIRE 16 -1 (3125 1825)(3250 1825);
WIRE 16 -1 (3250 1825)(4050 1825);
FORCEPROP 2 LAST SIG_NAME PWRGD_PVDDQ_KLM
J 0
(3310 1840);
DISPLAY 0.617021 (3310 1840);
PAINT ORANGE (3310 1840);
WIRE 16 -1 (3250 1825)(3250 2250);
WIRE 16 -1 (3750 975)(4050 975);
WIRE 16 -1 (3750 1975)(3750 975);
WIRE 16 -1 (2625 975)(3750 975);
FORCEPROP 2 LAST SIG_NAME SVID_DIO1_CPU1_R
J 0
(3075 985);
DISPLAY 0.617021 (3075 985);
PAINT ORANGE (3075 985);
WIRE 3 682 (3900 1150)(3850 1150);
WIRE 3 682 (3900 1200)(3900 1150);
WIRE 3 682 (3900 1200)(3850 1200);
WIRE 3 682 (3900 1525)(3350 1525);
WIRE 3 682 (3900 1525)(3900 1200);
WIRE 3 682 (3900 1525)(3950 1525);
WIRE 16 -1 (4050 1675)(2425 1675);
FORCEPROP 2 LAST SIG_NAME SVID_ALERT1_CPU1_R_N
J 0
(3300 1685);
DISPLAY 0.617021 (3300 1685);
PAINT ORANGE (3300 1685);
WIRE 16 -1 (4050 1725)(3125 1725);
FORCEPROP 2 LAST SIG_NAME IRQ_PVDDQ_KLM_VRHOT_LVT3_N
J 0
(3310 1740);
DISPLAY 0.617021 (3310 1740);
PAINT ORANGE (3310 1740);
WIRE 3 682 (2350 1250)(2500 1250);
WIRE 3 682 (2350 1350)(2350 1250);
WIRE 3 682 (2500 1250)(2500 1350);
WIRE 3 682 (2500 1350)(2350 1350);
WIRE 3 682 (600 425)(650 425);
WIRE 3 682 (600 625)(600 425);
WIRE 3 682 (650 625)(600 625);
WIRE 3 682 (1700 675)(1750 675);
WIRE 3 682 (1700 525)(1750 525);
WIRE 3 682 (1750 675)(1750 525);
WIRE 3 682 (1750 525)(1750 475);
WIRE 3 682 (1700 475)(1750 475);
WIRE 16 -1 (3100 -425)(3100 -350);
WIRE 16 -1 (3500 -350)(3100 -350);
FORCEPROP 2 LAST SIG_NAME VR_PVDDQ_KLM_VD12
J 0
(3185 -335);
DISPLAY 0.617021 (3185 -335);
PAINT ORANGE (3185 -335);
WIRE 16 -1 (3500 -425)(3500 -350);
WIRE 16 -1 (3500 -350)(4050 -350);
WIRE 16 -1 (-2025 475)(-2450 475);
FORCEPROP 2 LAST SIG_NAME VSENSE_PVDDQ_KLM_P
J 0
(-2465 490);
DISPLAY 0.617021 (-2465 490);
PAINT ORANGE (-2465 490);
WIRE 16 -1 (-1900 775)(-2450 775);
FORCEPROP 2 LAST SIG_NAME FM_PVDDQ_KLM_EN
J 0
(-2450 785);
DISPLAY 0.617021 (-2450 785);
PAINT ORANGE (-2450 785);
WIRE 3 682 (-1000 -100)(-1000 -550);
WIRE 3 682 (-600 -100)(-1000 -100);
WIRE 3 682 (-1000 -550)(-600 -550);
WIRE 3 682 (-600 -550)(-600 -100);
WIRE 3 682 (-100 -400)(-100 -900);
WIRE 3 682 (650 -400)(-100 -400);
WIRE 3 682 (-100 -900)(650 -900);
WIRE 3 682 (650 -900)(650 -400);
WIRE 3 2175 (-2900 2300)(-2350 2300);
WIRE 3 2175 (-2350 2050)(-2350 2300);
WIRE 3 2175 (-2900 2050)(-2900 2300);
WIRE 3 2175 (-2900 2050)(-2350 2050);
WIRE 16 -1 (725 1825)(575 1825);
WIRE 16 -1 (575 2525)(575 1825);
WIRE 16 -1 (575 2725)(575 2525);
WIRE 16 -1 (675 2525)(575 2525);
WIRE 16 -1 (675 2475)(675 2525);
WIRE 16 -1 (1275 2525)(675 2525);
FORCEPROP 2 LAST SIG_NAME VR_PVDDQ_KLM_VDD
J 0
(835 2540);
DISPLAY 0.617021 (835 2540);
PAINT ORANGE (835 2540);
FORCEPROP 2 LASTPROP $XRERR UNIQUE?
J 0
(595 2540);
DISPLAY 0.638298 (595 2540);
PAINT MONO (595 2540);
DISPLAY INVISIBLE (595 2540);
WIRE 16 -1 (1275 2475)(1275 2525);
WIRE 3 682 (-1100 3050)(-1100 2600);
WIRE 3 682 (-600 3050)(-1100 3050);
WIRE 3 682 (-1100 2600)(-600 2600);
WIRE 3 682 (-600 2600)(-600 3050);
WIRE 16 -1 (725 675)(-825 675);
WIRE 16 -1 (-825 200)(-825 675);
WIRE 16 -1 (-1750 225)(-1750 200);
WIRE 16 -1 (-1750 200)(-825 200);
WIRE 16 -1 (-2425 200)(-1750 200);
FORCEPROP 2 LAST SIG_NAME VSENSE_PVDDQ_KLM_N
J 0
(-2440 215);
DISPLAY 0.617021 (-2440 215);
PAINT ORANGE (-2440 215);
WIRE 16 -1 (725 1225)(-2450 1225);
FORCEPROP 2 LAST SIG_NAME VR_PVDDQ_KLM_VINSEN
J 0
(-2400 1240);
DISPLAY 0.617021 (-2400 1240);
PAINT ORANGE (-2400 1240);
WIRE 16 -1 (-650 2350)(-925 2350);
WIRE 16 -1 (-925 2750)(-925 2350);
WIRE 16 -1 (-2475 2350)(-925 2350);
FORCEPROP 0 LAST SIG_NAME SVID_CLK1_CPU1_R
J 0
(-2475 2360);
DISPLAY 0.617021 (-2475 2360);
PAINT ORANGE (-2475 2360);
WIRE 16 -1 (-1150 2025)(-1450 2025);
WIRE 16 -1 (-1475 1850)(-1150 1850);
WIRE 16 -1 (-1150 2025)(-1150 1850);
WIRE 16 -1 (-1150 1425)(-1150 1850);
WIRE 16 -1 (725 1425)(-1150 1425);
WIRE 16 -1 (-2450 1425)(-1150 1425);
FORCEPROP 2 LAST SIG_NAME ISENSE_PVDDQ_KLM_PH1_IMON
J 0
(-2425 1440);
DISPLAY 0.617021 (-2425 1440);
PAINT ORANGE (-2425 1440);
WIRE 16 -1 (-1000 2025)(-875 2025);
WIRE 16 -1 (-1000 1850)(-1000 2025);
WIRE 16 -1 (-825 1850)(-1000 1850);
WIRE 16 -1 (-1000 1575)(-1000 1850);
WIRE 16 -1 (725 1575)(-1000 1575);
WIRE 16 -1 (-2450 1575)(-1000 1575);
FORCEPROP 2 LAST SIG_NAME VR_PVDDQ_KLM_AIREF2
J 0
(-2365 1590);
DISPLAY 0.617021 (-2365 1590);
PAINT ORANGE (-2365 1590);
WIRE 16 -1 (-675 2025)(-450 2025);
WIRE 16 -1 (-675 1850)(-450 1850);
WIRE 16 -1 (-450 2025)(-450 1850);
WIRE 16 -1 (-450 1375)(-450 1850);
WIRE 16 -1 (-450 1375)(725 1375);
WIRE 16 -1 (-2450 1375)(-450 1375);
FORCEPROP 2 LAST SIG_NAME ISENSE_PVDDQ_KLM_PH2_IMON
J 0
(-2425 1390);
DISPLAY 0.617021 (-2425 1390);
PAINT ORANGE (-2425 1390);
WIRE 3 2175 (-400 1525)(-400 2200);
WIRE 3 2175 (-1800 2200)(-400 2200);
WIRE 3 2175 (-1800 1525)(-400 1525);
WIRE 3 2175 (-1800 1525)(-1800 2200);
WIRE 16 -1 (-1750 2025)(-1650 2025);
WIRE 16 -1 (-1750 2025)(-1750 1850);
WIRE 16 -1 (-1625 1850)(-1750 1850);
WIRE 16 -1 (-1750 1625)(-1750 1850);
WIRE 16 -1 (725 1625)(-1750 1625);
WIRE 16 -1 (-2450 1625)(-1750 1625);
FORCEPROP 2 LAST SIG_NAME VR_PVDDQ_KLM_AIREF1
J 0
(-2365 1640);
DISPLAY 0.617021 (-2365 1640);
PAINT ORANGE (-2365 1640);
WIRE 16 -1 (-175 775)(-175 2750);
WIRE 16 -1 (-175 775)(725 775);
WIRE 16 -1 (-1700 775)(-175 775);
FORCEPROP 2 LAST SIG_NAME VR_PVDDQ_KLM_VREN
J 0
(-1560 775);
DISPLAY 0.617021 (-1560 775);
PAINT ORANGE (-1560 775);
FORCEPROP 2 LASTPROP $XRERR UNIQUE?
J 0
(-1800 775);
DISPLAY 0.638298 (-1800 775);
PAINT MONO (-1800 775);
DISPLAY INVISIBLE (-1800 775);
WIRE 16 -1 (725 925)(-875 925);
WIRE 16 -1 (-875 475)(-875 925);
WIRE 16 -1 (-1825 475)(-1750 475);
WIRE 16 -1 (-1750 425)(-1750 475);
WIRE 16 -1 (-1750 475)(-875 475);
FORCEPROP 2 LAST SIG_NAME VR_PVDDQ_KLM_AVSP
J 0
(-1715 490);
DISPLAY 0.617021 (-1715 490);
PAINT ORANGE (-1715 490);
FORCEPROP 2 LASTPROP $XRERR UNIQUE?
J 0
(-1955 490);
DISPLAY 0.638298 (-1955 490);
PAINT MONO (-1955 490);
DISPLAY INVISIBLE (-1955 490);
WIRE 16 -1 (-225 125)(-225 1075);
WIRE 16 -1 (-225 1075)(725 1075);
WIRE 16 -1 (-2450 1075)(-225 1075);
FORCEPROP 2 LAST SIG_NAME A_TSENSE_PVDDQ_KLM
J 0
(-2400 1090);
DISPLAY 0.617021 (-2400 1090);
PAINT ORANGE (-2400 1090);
WIRE 16 -1 (-2450 1175)(725 1175);
FORCEPROP 2 LAST SIG_NAME VR_PVDDQ_KLM_AIINSEN
J 0
(-2410 1185);
DISPLAY 0.617021 (-2410 1185);
PAINT ORANGE (-2410 1185);
WIRE 16 -1 (1825 1725)(1625 1725);
WIRE 16 -1 (1825 2250)(1825 1725);
WIRE 16 -1 (2925 1725)(1825 1725);
FORCEPROP 2 LAST SIG_NAME IRQ_PVDDQ_KLM_VRHOT_LVT3_R_N
J 0
(1735 1740);
DISPLAY 0.617021 (1735 1740);
PAINT ORANGE (1735 1740);
FORCEPROP 2 LASTPROP $XRERR UNIQUE?
J 0
(1495 1740);
DISPLAY 0.638298 (1495 1740);
PAINT MONO (1495 1740);
DISPLAY INVISIBLE (1495 1740);
WIRE 16 -1 (2650 375)(2650 1825);
WIRE 16 -1 (2925 1825)(2650 1825);
WIRE 16 -1 (1625 1825)(2100 1825);
WIRE 16 -1 (2100 2250)(2100 1825);
WIRE 16 -1 (2600 1825)(2100 1825);
FORCEPROP 2 LAST SIG_NAME PWRGD_PVDDQ_KLM_R
J 0
(2160 1840);
DISPLAY 0.617021 (2160 1840);
PAINT ORANGE (2160 1840);
WIRE 16 -1 (2650 1825)(2600 1825);
WIRE 16 -1 (2600 2100)(2600 1825);
WIRE 16 -1 (2650 2100)(2600 2100);
WIRE 3 682 (3200 2550)(3200 2150);
WIRE 3 682 (3550 2550)(3200 2550);
WIRE 3 682 (3200 2150)(3550 2150);
WIRE 3 682 (3550 2150)(3550 2550);
WIRE 16 2175 (3650 2550)(3650 3050);
WIRE 16 2175 (4800 2550)(3650 2550);
WIRE 16 2175 (4800 3050)(3650 3050);
WIRE 16 2175 (4800 3050)(4800 2550);
DOT 1 (-450 1375);
DOT 1 (1825 1725);
DOT 1 (3250 1825);
DOT 1 (3900 1200);
DOT 1 (3250 1175);
DOT 1 (-450 1850);
DOT 1 (-1750 1850);
DOT 1 (3900 1525);
DOT 1 (3250 1525);
DOT 1 (2100 2825);
DOT 1 (2200 2825);
DOT 1 (2650 1825);
DOT 1 (2600 1825);
DOT 1 (2100 1825);
DOT 1 (3500 -350);
DOT 1 (675 2525);
DOT 1 (575 2525);
DOT 1 (250 3100);
DOT 1 (1750 275);
DOT 1 (-225 1075);
DOT 1 (-1750 475);
DOT 1 (-1750 200);
DOT 1 (1750 525);
DOT 1 (3750 975);
DOT 1 (-925 2350);
DOT 1 (-1750 1625);
DOT 1 (-1000 1575);
DOT 1 (-1000 1850);
DOT 1 (-1150 1425);
DOT 1 (-1150 1850);
DOT 1 (-175 775);
FORCENOTE
IOUT DI/DT = 15A/US/18.09A/US FOR DS/SS
(3675 2625) 0;
DISPLAY LEFT (3675 2625);
DISPLAY 0.808511 (3675 2625);
PAINT PURPLE (3675 2625);
FORCENOTE
SW FREQ = 833.33KHZ
(3675 2575) 0;
DISPLAY LEFT (3675 2575);
DISPLAY 0.808511 (3675 2575);
PAINT PURPLE (3675 2575);
FORCENOTE
VOUT = 1.2V 
(3675 2975) 0;
DISPLAY LEFT (3675 2975);
DISPLAY 0.808511 (3675 2975);
PAINT PURPLE (3675 2975);
FORCENOTE
DC TOL = +/-0.5%
(3675 2875) 0;
DISPLAY LEFT (3675 2875);
DISPLAY 0.808511 (3675 2875);
PAINT PURPLE (3675 2875);
FORCENOTE
IOUT TDC = 65.7A/25.86A FOR DS/SS
(3675 2775) 0;
DISPLAY LEFT (3675 2775);
DISPLAY 0.808511 (3675 2775);
PAINT PURPLE (3675 2775);
FORCENOTE
IOUT PK = 73A/29.38A FOR DS/SS
(3675 2725) 0;
DISPLAY LEFT (3675 2725);
DISPLAY 0.808511 (3675 2725);
PAINT PURPLE (3675 2725);
FORCENOTE
IOUT STEP = 45A/17.96A FOR DS/SS
(3675 2675) 0;
DISPLAY LEFT (3675 2675);
DISPLAY 0.808511 (3675 2675);
PAINT PURPLE (3675 2675);
FORCENOTE
RIPPLE GUIDELINE = +/- 0.5%
(3675 2925) 0;
DISPLAY LEFT (3675 2925);
DISPLAY 0.808511 (3675 2925);
PAINT PURPLE (3675 2925);
FORCENOTE
AC & RIPPLE TOL = +/2.8%
(3675 2825) 0;
DISPLAY LEFT (3675 2825);
DISPLAY 0.808511 (3675 2825);
PAINT PURPLE (3675 2825);
FORCENOTE
TP FAB3 NOPOP R1B5 0919
(2750 2025) 0;
DISPLAY LEFT (2750 2025);
DISPLAY 0.638298 (2750 2025);
PAINT RED (2750 2025);
FORCENOTE
TP FAB1 NC 0321
(-25 1000) 0;
DISPLAY LEFT (-25 1000);
DISPLAY 1.021277 (-25 1000);
PAINT RED (-25 1000);
FORCENOTE
TP FAB1 CO-LAY WITH FAIRCHILD PARTS 1203
(-1787 1481) 0;
DISPLAY LEFT (-1787 1481);
DISPLAY 0.638298 (-1787 1481);
PAINT RED (-1787 1481);
FORCENOTE
TP FAB4 NOPOP RF22 AND CF22 FOR SS BOM 20170124
(-1050 1425) 0;
DISPLAY LEFT (-1050 1425);
DISPLAY 0.638298 (-1050 1425);
PAINT RED (-1050 1425);
FORCENOTE
RF21&RF22
(-2875 2225) 0;
DISPLAY LEFT (-2875 2225);
DISPLAY 0.872340 (-2875 2225);
PAINT RED (-2875 2225);
FORCENOTE
FAIRCHILD:POP
(-2875 2075) 0;
DISPLAY LEFT (-2875 2075);
DISPLAY 0.872340 (-2875 2075);
PAINT RED (-2875 2075);
FORCENOTE
INFINEON:NOPOP
(-2875 2125) 0;
DISPLAY LEFT (-2875 2125);
DISPLAY 0.872340 (-2875 2125);
PAINT RED (-2875 2125);
FORCENOTE
CF21&CF22
(-2875 2175) 0;
DISPLAY LEFT (-2875 2175);
DISPLAY 0.872340 (-2875 2175);
PAINT RED (-2875 2175);
FORCENOTE
TP FAB1 DEL CAP 0218
(-1100 -650) 0;
DISPLAY LEFT (-1100 -650);
DISPLAY 1.021277 (-1100 -650);
PAINT RED (-1100 -650);
FORCENOTE
TP FAB1 CHANGE R1B12 RES AND NOPOP R1B15 0408
(-100 -950) 0;
DISPLAY LEFT (-100 -950);
DISPLAY 0.638298 (-100 -950);
PAINT RED (-100 -950);
FORCENOTE
TP FAB1 NC 0321
(-25 875) 0;
DISPLAY LEFT (-25 875);
DISPLAY 1.021277 (-25 875);
PAINT RED (-25 875);
FORCENOTE
TP FAB1 NC 0321
(1725 1450) 0;
DISPLAY LEFT (1725 1450);
DISPLAY 1.021277 (1725 1450);
PAINT RED (1725 1450);
FORCENOTE
TP FAB3 POP R12W34 0919
(4000 1475) 0;
DISPLAY LEFT (4000 1475);
DISPLAY 0.638298 (4000 1475);
PAINT RED (4000 1475);
FORCENOTE
TP FAB1 ADD RES 0303
(4000 1525) 0;
DISPLAY LEFT (4000 1525);
DISPLAY 0.638298 (4000 1525);
PAINT RED (4000 1525);
FORCENOTE
TP FAB1 DEL RES 0314
(2100 1375) 0;
DISPLAY LEFT (2100 1375);
DISPLAY 1.021277 (2100 1375);
PAINT RED (2100 1375);
FORCENOTE
TP FAB1 CHANGE R1B15 RES 0815
(-100 -1050) 0;
DISPLAY LEFT (-100 -1050);
DISPLAY 0.638298 (-100 -1050);
PAINT RED (-100 -1050);
FORCENOTE
TP FAB1 CHANGE R1B12 RES 0523
(-100 -1000) 0;
DISPLAY LEFT (-100 -1000);
DISPLAY 0.638298 (-100 -1000);
PAINT RED (-100 -1000);
FORCENOTE
TP FAB1 DELETE RES 0203
(-2800 1775) 0;
DISPLAY LEFT (-2800 1775);
DISPLAY 1.021277 (-2800 1775);
PAINT RED (-2800 1775);
FORCENOTE
TP FAB1 NC 0321
(1800 650) 0;
DISPLAY LEFT (1800 650);
DISPLAY 1.021277 (1800 650);
PAINT RED (1800 650);
FORCENOTE
TP FAB1 NC 0321
(-25 600) 0;
DISPLAY LEFT (-25 600);
DISPLAY 1.021277 (-25 600);
PAINT RED (-25 600);
FORCENOTE
ROOM=VDDQ_KLM_PWR_VR
(-2980 -1415) 0;
DISPLAY LEFT (-2980 -1415);
DISPLAY 2.446809 (-2980 -1415);
PAINT PURPLE (-2980 -1415);
FORCENOTE
TP FAB1 NC 0321
(1700 825) 0;
DISPLAY LEFT (1700 825);
DISPLAY 1.021277 (1700 825);
PAINT RED (1700 825);
FORCENOTE
TP FAB3 POP R1B13 1014
(3200 2575) 0;
DISPLAY LEFT (3200 2575);
DISPLAY 0.638298 (3200 2575);
PAINT RED (3200 2575);
FORCENOTE
TP FAB1 NC 0321
(250 1525) 0;
DISPLAY LEFT (250 1525);
DISPLAY 0.638298 (250 1525);
PAINT RED (250 1525);
FORCENOTE
TP FAB1 NOPOP RES 0316
(-1250 3075) 0;
DISPLAY LEFT (-1250 3075);
DISPLAY 1.021277 (-1250 3075);
PAINT RED (-1250 3075);
FORCENOTE
TP FAB1 NC 0321
(-75 1300) 0;
DISPLAY LEFT (-75 1300);
DISPLAY 1.021277 (-75 1300);
PAINT RED (-75 1300);
FORCENOTE
TP FAB4 CHANGE RF21 TO 909OHM FOR VR FAILCHILD, SINGLE SIDE BOM 20170123
(-1800 2200) 0;
DISPLAY LEFT (-1800 2200);
DISPLAY 0.638298 (-1800 2200);
PAINT RED (-1800 2200);
QUIT
